FILE_TYPE = MACRO_DRAWING;
SET COLOR_WIRE YELLOW;
SET COLOR_PROP ORANGE;
SET COLOR_DOT WHITE;
SET COLOR_ARC YELLOW;
SET COLOR_BODY GREEN;
SET COLOR_NOTE PURPLE;
SET PROP_DISPLAY VALUE;
SET PAGE_NUMBER P150;
FORCEADD OFFPAGE..1
(-7625 5650);
FORCEPROP 2 LAST $XR0 172 
J 0
(-7877 5650);
DISPLAY 0.638298 (-7877 5650);
PAINT MONO (-7877 5650);
FORCEPROP 2 LAST CDS_LIB standard
J 2
(-7625 5650);
DISPLAY INVISIBLE (-7625 5650);
FORCEPROP 1 LAST OFFPAGE TRUE
J 0
(-7300 5525);
DISPLAY 0.872340 (-7300 5525);
PAINT GREEN (-7300 5525);
DISPLAY INVISIBLE (-7300 5525);
FORCEPROP 1 LAST COMMENT_BODY TRUE
J 0
(-7500 5550);
DISPLAY 0.872340 (-7500 5550);
PAINT GREEN (-7500 5550);
DISPLAY INVISIBLE (-7500 5550);
FORCEPROP 2 LAST PATH I10
J 2
(-7800 5725);
DISPLAY 1.021277 (-7800 5725);
DISPLAY INVISIBLE (-7800 5725);
FORCEADD OFFPAGE..1
(-7625 5550);
FORCEPROP 2 LAST $XR0 172 
J 0
(-7877 5550);
DISPLAY 0.638298 (-7877 5550);
PAINT MONO (-7877 5550);
FORCEPROP 2 LAST CDS_LIB standard
J 0
(-7625 5550);
DISPLAY INVISIBLE (-7625 5550);
FORCEPROP 1 LAST OFFPAGE TRUE
J 0
(-7300 5425);
DISPLAY 0.872340 (-7300 5425);
PAINT GREEN (-7300 5425);
DISPLAY INVISIBLE (-7300 5425);
FORCEPROP 1 LAST COMMENT_BODY TRUE
J 0
(-7500 5450);
DISPLAY 0.872340 (-7500 5450);
PAINT GREEN (-7500 5450);
DISPLAY INVISIBLE (-7500 5450);
FORCEPROP 2 LAST PATH I11
J 0
(-7575 5625);
DISPLAY 1.021277 (-7575 5625);
DISPLAY INVISIBLE (-7575 5625);
FORCEADD OFFPAGE..1
(-7625 5600);
FORCEPROP 2 LAST $XR0 172 
J 0
(-7877 5600);
DISPLAY 0.638298 (-7877 5600);
PAINT MONO (-7877 5600);
FORCEPROP 2 LAST CDS_LIB standard
J 0
(-7625 5600);
DISPLAY INVISIBLE (-7625 5600);
FORCEPROP 1 LAST OFFPAGE TRUE
J 0
(-7300 5475);
DISPLAY 0.872340 (-7300 5475);
PAINT GREEN (-7300 5475);
DISPLAY INVISIBLE (-7300 5475);
FORCEPROP 1 LAST COMMENT_BODY TRUE
J 0
(-7500 5500);
DISPLAY 0.872340 (-7500 5500);
PAINT GREEN (-7500 5500);
DISPLAY INVISIBLE (-7500 5500);
FORCEPROP 2 LAST PATH I12
J 0
(-7575 5675);
DISPLAY 1.021277 (-7575 5675);
DISPLAY INVISIBLE (-7575 5675);
FORCEADD GND..1
(-4650 5875);
FORCEPROP 3 LASTPIN (-4650 5925) SIG_NAME GND\g
J 0
(-4640 5935);
DISPLAY 0.659574 (-4640 5935);
PAINT MONO (-4640 5935);
DISPLAY INVISIBLE (-4640 5935);
FORCEPROP 2 LAST CDS_LIB pure_quanta_power
J 0
(-4650 5875);
DISPLAY INVISIBLE (-4650 5875);
FORCEPROP 1 LAST SIZE 1B
J 0
(-4575 5825);
DISPLAY 0.872340 (-4575 5825);
PAINT GREEN (-4575 5825);
DISPLAY INVISIBLE (-4575 5825);
FORCEPROP 1 LAST HDL_POWER GND
J 0
(-4650 6025);
DISPLAY 0.872340 (-4650 6025);
PAINT GREEN (-4650 6025);
DISPLAY INVISIBLE (-4650 6025);
FORCEPROP 1 LAST PATH I13
J 0
(-4575 5875);
DISPLAY 0.872340 (-4575 5875);
PAINT AQUA (-4575 5875);
DISPLAY INVISIBLE (-4575 5875);
FORCEADD Q_CAP..1
(-4650 6100);
FORCEPROP 1 LAST LOCATION C1516
J 0
(-4550 6250);
DISPLAY 0.489362 (-4550 6250);
PAINT SKYBLUE (-4550 6250);
FORCEPROP 2 LAST $SEC 1
J 0
(-4600 6300);
PAINT MONO (-4600 6300);
DISPLAY INVISIBLE (-4600 6300);
FORCEPROP 2 LAST CDS_SEC 1
J 0
(-4600 6300);
PAINT MONO (-4600 6300);
DISPLAY INVISIBLE (-4600 6300);
FORCEPROP 1 LASTPIN (-4650 6200) $PN 1
J 0
(-4640 6180);
DISPLAY 0.489362 (-4640 6180);
PAINT GREEN (-4640 6180);
FORCEPROP 1 LASTPIN (-4650 6000) $PN 2
J 0
(-4640 5980);
DISPLAY 0.489362 (-4640 5980);
PAINT GREEN (-4640 5980);
FORCEPROP 1 LAST MATERIAL X7R
J 0
(-4550 6050);
DISPLAY 0.489362 (-4550 6050);
PAINT SKYBLUE (-4550 6050);
FORCEPROP 1 LAST TOLERANCE 10%
J 0
(-4550 6100);
DISPLAY 0.489362 (-4550 6100);
PAINT SKYBLUE (-4550 6100);
FORCEPROP 1 LAST VALUE 0.1UF
J 0
(-4550 6200);
DISPLAY 0.489362 (-4550 6200);
PAINT SKYBLUE (-4550 6200);
FORCEPROP 1 LAST VOLTAGE 16V
J 0
(-4550 6150);
DISPLAY 0.489362 (-4550 6150);
PAINT SKYBLUE (-4550 6150);
FORCEPROP 1 LAST PACK_TYPE C0402
J 0
(-4550 5950);
DISPLAY 0.489362 (-4550 5950);
PAINT SKYBLUE (-4550 5950);
FORCEPROP 2 LAST CDS_LIB pure_quanta
J 0
(-4650 6100);
DISPLAY INVISIBLE (-4650 6100);
FORCEPROP 1 LAST PATH I14
J 0
(-4600 6250);
DISPLAY 0.978723 (-4600 6250);
PAINT WHITE (-4600 6250);
DISPLAY INVISIBLE (-4600 6250);
FORCEPROP 1 LAST PART_NUMBER CH4103K1B08
J 0
(-4550 6000);
DISPLAY 0.489362 (-4550 6000);
PAINT SKYBLUE (-4550 6000);
DISPLAY INVISIBLE (-4550 6000);
FORCEADD UNIVERSAL_POWER..1
(-4800 6425);
FORCEPROP 3 LASTPIN (-4800 6375) SIG_NAME PVDD18_S5_P0\g
J 0
(-4790 6385);
DISPLAY 0.659574 (-4790 6385);
PAINT MONO (-4790 6385);
DISPLAY INVISIBLE (-4790 6385);
FORCEPROP 1 LAST HDL_POWER PVDD18_S5_P0
J 1
(-4800 6475);
DISPLAY 0.489362 (-4800 6475);
PAINT GREEN (-4800 6475);
FORCEPROP 2 LAST CDS_LIB pure_quanta_power
J 0
(-4800 6425);
PAINT MONO (-4800 6425);
DISPLAY INVISIBLE (-4800 6425);
FORCEPROP 1 LAST PATH I15
J 0
(-4750 6450);
DISPLAY 0.872340 (-4750 6450);
PAINT AQUA (-4750 6450);
DISPLAY INVISIBLE (-4750 6450);
FORCEADD GND..1
(-4800 4975);
FORCEPROP 3 LASTPIN (-4800 5025) SIG_NAME GND\g
J 0
(-4790 5035);
DISPLAY 0.659574 (-4790 5035);
PAINT MONO (-4790 5035);
DISPLAY INVISIBLE (-4790 5035);
FORCEPROP 1 LAST SIZE 1B
J 0
(-4725 4925);
DISPLAY 0.872340 (-4725 4925);
PAINT GREEN (-4725 4925);
DISPLAY INVISIBLE (-4725 4925);
FORCEPROP 2 LAST CDS_LIB pure_quanta_power
J 0
(-4800 4975);
PAINT MONO (-4800 4975);
DISPLAY INVISIBLE (-4800 4975);
FORCEPROP 1 LAST HDL_POWER GND
J 0
(-4800 5125);
DISPLAY 0.872340 (-4800 5125);
PAINT GREEN (-4800 5125);
DISPLAY INVISIBLE (-4800 5125);
FORCEPROP 1 LAST PATH I16
J 0
(-4725 4975);
DISPLAY 0.872340 (-4725 4975);
PAINT AQUA (-4725 4975);
DISPLAY INVISIBLE (-4725 4975);
FORCEADD GND..1
(-6050 5925);
FORCEPROP 3 LASTPIN (-6050 5975) SIG_NAME GND\g
J 0
(-6040 5985);
DISPLAY 0.659574 (-6040 5985);
PAINT MONO (-6040 5985);
DISPLAY INVISIBLE (-6040 5985);
FORCEPROP 1 LAST SIZE 1B
J 0
(-5975 5875);
DISPLAY 0.872340 (-5975 5875);
PAINT GREEN (-5975 5875);
DISPLAY INVISIBLE (-5975 5875);
FORCEPROP 2 LAST CDS_LIB pure_quanta_power
J 0
(-6050 5925);
DISPLAY INVISIBLE (-6050 5925);
FORCEPROP 1 LAST HDL_POWER GND
J 0
(-6050 6075);
DISPLAY 0.872340 (-6050 6075);
PAINT GREEN (-6050 6075);
DISPLAY INVISIBLE (-6050 6075);
FORCEPROP 1 LAST PATH I17
J 0
(-5975 5925);
DISPLAY 0.872340 (-5975 5925);
PAINT AQUA (-5975 5925);
DISPLAY INVISIBLE (-5975 5925);
FORCEADD UNIVERSAL_POWER..1
(-5850 6425);
FORCEPROP 3 LASTPIN (-5850 6375) SIG_NAME PVDD18_S5_P0\g
J 0
(-5840 6385);
DISPLAY 0.659574 (-5840 6385);
PAINT MONO (-5840 6385);
DISPLAY INVISIBLE (-5840 6385);
FORCEPROP 1 LAST HDL_POWER PVDD18_S5_P0
J 1
(-5850 6475);
DISPLAY 0.489362 (-5850 6475);
PAINT GREEN (-5850 6475);
FORCEPROP 2 LAST CDS_LIB pure_quanta_power
J 0
(-5850 6425);
PAINT MONO (-5850 6425);
DISPLAY INVISIBLE (-5850 6425);
FORCEPROP 1 LAST PATH I18
J 0
(-5800 6450);
DISPLAY 0.872340 (-5800 6450);
PAINT AQUA (-5800 6450);
DISPLAY INVISIBLE (-5800 6450);
FORCEADD Q_CAP..1
(-6050 6100);
FORCEPROP 1 LAST LOCATION C1514
J 0
(-6200 6225);
DISPLAY 0.489362 (-6200 6225);
PAINT SKYBLUE (-6200 6225);
FORCEPROP 2 LAST $SEC 1
J 0
(-6000 6300);
PAINT MONO (-6000 6300);
DISPLAY INVISIBLE (-6000 6300);
FORCEPROP 2 LAST CDS_SEC 1
J 0
(-6000 6300);
PAINT MONO (-6000 6300);
DISPLAY INVISIBLE (-6000 6300);
FORCEPROP 1 LASTPIN (-6050 6200) $PN 1
J 0
(-6040 6180);
DISPLAY 0.489362 (-6040 6180);
PAINT GREEN (-6040 6180);
FORCEPROP 1 LASTPIN (-6050 6000) $PN 2
J 0
(-6040 5980);
DISPLAY 0.489362 (-6040 5980);
PAINT GREEN (-6040 5980);
FORCEPROP 1 LAST MATERIAL X7R
J 0
(-6175 6025);
DISPLAY 0.489362 (-6175 6025);
PAINT SKYBLUE (-6175 6025);
FORCEPROP 1 LAST TOLERANCE 10%
J 0
(-6175 6075);
DISPLAY 0.489362 (-6175 6075);
PAINT SKYBLUE (-6175 6075);
FORCEPROP 1 LAST VALUE 0.1UF
J 0
(-6225 6175);
DISPLAY 0.489362 (-6225 6175);
PAINT SKYBLUE (-6225 6175);
FORCEPROP 1 LAST VOLTAGE 16V
J 0
(-6175 6125);
DISPLAY 0.489362 (-6175 6125);
PAINT SKYBLUE (-6175 6125);
FORCEPROP 1 LAST PACK_TYPE C0402
J 0
(-6225 5925);
DISPLAY 0.489362 (-6225 5925);
PAINT SKYBLUE (-6225 5925);
FORCEPROP 2 LAST CDS_LIB pure_quanta
J 0
(-6050 6100);
DISPLAY INVISIBLE (-6050 6100);
FORCEPROP 1 LAST PATH I19
J 0
(-6000 6250);
DISPLAY 0.978723 (-6000 6250);
PAINT WHITE (-6000 6250);
DISPLAY INVISIBLE (-6000 6250);
FORCEPROP 1 LAST PART_NUMBER CH4103K1B08
J 0
(-6400 5975);
DISPLAY 0.489362 (-6400 5975);
PAINT SKYBLUE (-6400 5975);
DISPLAY INVISIBLE (-6400 5975);
FORCEADD OFFPAGE..2
(-2375 5700);
FORCEPROP 2 LAST $XR0 27 
J 0
(-2186 5700);
DISPLAY 0.638298 (-2186 5700);
PAINT MONO (-2186 5700);
FORCEPROP 2 LAST CDS_LIB standard
J 0
(-2375 5700);
PAINT MONO (-2375 5700);
DISPLAY INVISIBLE (-2375 5700);
FORCEPROP 1 LAST OFFPAGE TRUE
J 0
(-2050 5575);
DISPLAY 0.872340 (-2050 5575);
PAINT GREEN (-2050 5575);
DISPLAY INVISIBLE (-2050 5575);
FORCEPROP 1 LAST COMMENT_BODY TRUE
J 0
(-2420 5605);
DISPLAY 0.872340 (-2420 5605);
PAINT GREEN (-2420 5605);
DISPLAY INVISIBLE (-2420 5605);
FORCEPROP 2 LAST PATH I20
J 0
(-2175 5750);
DISPLAY 1.021277 (-2175 5750);
DISPLAY INVISIBLE (-2175 5750);
FORCEADD OFFPAGE..2
(-2375 5550);
FORCEPROP 2 LAST $XR0 27 
J 0
(-2186 5550);
DISPLAY 0.638298 (-2186 5550);
PAINT MONO (-2186 5550);
FORCEPROP 2 LAST CDS_LIB standard
J 0
(-2375 5550);
PAINT MONO (-2375 5550);
DISPLAY INVISIBLE (-2375 5550);
FORCEPROP 1 LAST OFFPAGE TRUE
J 0
(-2050 5425);
DISPLAY 0.872340 (-2050 5425);
PAINT GREEN (-2050 5425);
DISPLAY INVISIBLE (-2050 5425);
FORCEPROP 1 LAST COMMENT_BODY TRUE
J 0
(-2420 5455);
DISPLAY 0.872340 (-2420 5455);
PAINT GREEN (-2420 5455);
DISPLAY INVISIBLE (-2420 5455);
FORCEPROP 2 LAST PATH I21
J 0
(-2175 5600);
DISPLAY 1.021277 (-2175 5600);
DISPLAY INVISIBLE (-2175 5600);
FORCEADD OFFPAGE..2
(-2375 5600);
FORCEPROP 2 LAST $XR0 27 
J 0
(-2186 5600);
DISPLAY 0.638298 (-2186 5600);
PAINT MONO (-2186 5600);
FORCEPROP 2 LAST CDS_LIB standard
J 0
(-2375 5600);
PAINT MONO (-2375 5600);
DISPLAY INVISIBLE (-2375 5600);
FORCEPROP 1 LAST OFFPAGE TRUE
J 0
(-2050 5475);
DISPLAY 0.872340 (-2050 5475);
PAINT GREEN (-2050 5475);
DISPLAY INVISIBLE (-2050 5475);
FORCEPROP 1 LAST COMMENT_BODY TRUE
J 0
(-2420 5505);
DISPLAY 0.872340 (-2420 5505);
PAINT GREEN (-2420 5505);
DISPLAY INVISIBLE (-2420 5505);
FORCEPROP 2 LAST PATH I22
J 0
(-2175 5650);
DISPLAY 1.021277 (-2175 5650);
DISPLAY INVISIBLE (-2175 5650);
FORCEADD OFFPAGE..2
(-2375 5650);
FORCEPROP 2 LAST $XR0 27 
J 0
(-2186 5650);
DISPLAY 0.638298 (-2186 5650);
PAINT MONO (-2186 5650);
FORCEPROP 2 LAST CDS_LIB standard
J 0
(-2375 5650);
PAINT MONO (-2375 5650);
DISPLAY INVISIBLE (-2375 5650);
FORCEPROP 1 LAST OFFPAGE TRUE
J 0
(-2050 5525);
DISPLAY 0.872340 (-2050 5525);
PAINT GREEN (-2050 5525);
DISPLAY INVISIBLE (-2050 5525);
FORCEPROP 1 LAST COMMENT_BODY TRUE
J 0
(-2420 5555);
DISPLAY 0.872340 (-2420 5555);
PAINT GREEN (-2420 5555);
DISPLAY INVISIBLE (-2420 5555);
FORCEPROP 2 LAST PATH I23
J 0
(-2175 5700);
DISPLAY 1.021277 (-2175 5700);
DISPLAY INVISIBLE (-2175 5700);
FORCEADD Q_RES..1
(-3625 5550);
FORCEPROP 1 LAST LOCATION R1641
J 0
(-4000 5550);
DISPLAY 0.489362 (-4000 5550);
PAINT SKYBLUE (-4000 5550);
FORCEPROP 0 LAST $SEC 1
J 0
(-3875 5600);
PAINT MONO (-3875 5600);
DISPLAY INVISIBLE (-3875 5600);
FORCEPROP 0 LAST CDS_SEC 1
J 0
(-3875 5600);
PAINT MONO (-3875 5600);
DISPLAY INVISIBLE (-3875 5600);
FORCEPROP 1 LASTPIN (-3725 5550) $PN 1
J 0
(-3713 5562);
DISPLAY 0.489362 (-3713 5562);
PAINT GREEN (-3713 5562);
FORCEPROP 1 LASTPIN (-3525 5550) $PN 2
J 0
(-3563 5562);
DISPLAY 0.489362 (-3563 5562);
PAINT GREEN (-3563 5562);
FORCEPROP 1 LAST VALUE 22
J 2
(-3725 5550);
DISPLAY 0.489362 (-3725 5550);
PAINT SKYBLUE (-3725 5550);
FORCEPROP 1 LAST TOLERANCE 1%
J 0
(-3525 5525);
DISPLAY 0.489362 (-3525 5525);
PAINT SKYBLUE (-3525 5525);
FORCEPROP 1 LAST MATERIAL CHIP
J 0
(-3800 5525);
DISPLAY 0.489362 (-3800 5525);
PAINT SKYBLUE (-3800 5525);
FORCEPROP 1 LAST PACK_TYPE 0402LF
J 0
(-3375 5400);
DISPLAY 0.978723 (-3375 5400);
PAINT SKYBLUE (-3375 5400);
DISPLAY INVISIBLE (-3375 5400);
FORCEPROP 1 LAST WATTAGE 1/16W
J 2
(-3650 5400);
DISPLAY 0.978723 (-3650 5400);
PAINT SKYBLUE (-3650 5400);
DISPLAY INVISIBLE (-3650 5400);
FORCEPROP 2 LAST CDS_LIB pure_quanta
J 0
(-3625 5550);
PAINT MONO (-3625 5550);
DISPLAY INVISIBLE (-3625 5550);
FORCEPROP 1 LAST PATH I24
J 0
(-3675 5700);
DISPLAY 0.978723 (-3675 5700);
PAINT WHITE (-3675 5700);
DISPLAY INVISIBLE (-3675 5700);
FORCEPROP 1 LAST PART_NUMBER CS02202FB02
J 0
(-3675 5650);
DISPLAY 0.978723 (-3675 5650);
PAINT SKYBLUE (-3675 5650);
DISPLAY INVISIBLE (-3675 5650);
FORCEADD Q_RES..1
(-3625 5650);
FORCEPROP 1 LAST LOCATION R1639
J 0
(-4000 5650);
DISPLAY 0.489362 (-4000 5650);
PAINT SKYBLUE (-4000 5650);
FORCEPROP 0 LAST $SEC 1
J 0
(-3950 5700);
DISPLAY 0.680851 (-3950 5700);
PAINT MONO (-3950 5700);
DISPLAY INVISIBLE (-3950 5700);
FORCEPROP 0 LAST CDS_SEC 1
J 0
(-3950 5700);
DISPLAY 1.021277 (-3950 5700);
DISPLAY INVISIBLE (-3950 5700);
FORCEPROP 1 LASTPIN (-3725 5650) $PN 1
J 0
(-3713 5662);
DISPLAY 0.489362 (-3713 5662);
PAINT MONO (-3713 5662);
FORCEPROP 1 LASTPIN (-3525 5650) $PN 2
J 0
(-3563 5662);
DISPLAY 0.489362 (-3563 5662);
PAINT MONO (-3563 5662);
FORCEPROP 1 LAST VALUE 22
J 2
(-3725 5650);
DISPLAY 0.489362 (-3725 5650);
PAINT SKYBLUE (-3725 5650);
FORCEPROP 1 LAST TOLERANCE 1%
J 0
(-3525 5625);
DISPLAY 0.489362 (-3525 5625);
PAINT SKYBLUE (-3525 5625);
FORCEPROP 1 LAST MATERIAL CHIP
J 0
(-3800 5625);
DISPLAY 0.489362 (-3800 5625);
PAINT SKYBLUE (-3800 5625);
FORCEPROP 1 LAST PACK_TYPE 0402LF
J 0
(-3375 5500);
DISPLAY 0.978723 (-3375 5500);
PAINT SKYBLUE (-3375 5500);
DISPLAY INVISIBLE (-3375 5500);
FORCEPROP 1 LAST WATTAGE 1/16W
J 2
(-3650 5500);
DISPLAY 0.978723 (-3650 5500);
PAINT SKYBLUE (-3650 5500);
DISPLAY INVISIBLE (-3650 5500);
FORCEPROP 2 LAST CDS_LIB pure_quanta
J 0
(-3625 5650);
DISPLAY INVISIBLE (-3625 5650);
FORCEPROP 1 LAST PATH I25
J 0
(-3675 5800);
DISPLAY 0.978723 (-3675 5800);
PAINT WHITE (-3675 5800);
DISPLAY INVISIBLE (-3675 5800);
FORCEPROP 1 LAST PART_NUMBER CS02202FB02
J 0
(-3675 5750);
DISPLAY 0.978723 (-3675 5750);
PAINT SKYBLUE (-3675 5750);
DISPLAY INVISIBLE (-3675 5750);
FORCEADD Q_RES..1
(-3625 5600);
FORCEPROP 1 LAST LOCATION R1640
J 0
(-4000 5600);
DISPLAY 0.489362 (-4000 5600);
PAINT SKYBLUE (-4000 5600);
FORCEPROP 0 LAST $SEC 1
J 0
(-3875 5650);
PAINT MONO (-3875 5650);
DISPLAY INVISIBLE (-3875 5650);
FORCEPROP 0 LAST CDS_SEC 1
J 0
(-3875 5650);
PAINT MONO (-3875 5650);
DISPLAY INVISIBLE (-3875 5650);
FORCEPROP 1 LASTPIN (-3725 5600) $PN 1
J 0
(-3713 5612);
DISPLAY 0.489362 (-3713 5612);
PAINT GREEN (-3713 5612);
FORCEPROP 1 LASTPIN (-3525 5600) $PN 2
J 0
(-3563 5612);
DISPLAY 0.489362 (-3563 5612);
PAINT GREEN (-3563 5612);
FORCEPROP 1 LAST VALUE 22
J 2
(-3725 5600);
DISPLAY 0.489362 (-3725 5600);
PAINT SKYBLUE (-3725 5600);
FORCEPROP 1 LAST TOLERANCE 1%
J 0
(-3525 5575);
DISPLAY 0.489362 (-3525 5575);
PAINT SKYBLUE (-3525 5575);
FORCEPROP 1 LAST MATERIAL CHIP
J 0
(-3800 5575);
DISPLAY 0.489362 (-3800 5575);
PAINT SKYBLUE (-3800 5575);
FORCEPROP 1 LAST PACK_TYPE 0402LF
J 0
(-3375 5450);
DISPLAY 0.978723 (-3375 5450);
PAINT SKYBLUE (-3375 5450);
DISPLAY INVISIBLE (-3375 5450);
FORCEPROP 1 LAST WATTAGE 1/16W
J 2
(-3650 5450);
DISPLAY 0.978723 (-3650 5450);
PAINT SKYBLUE (-3650 5450);
DISPLAY INVISIBLE (-3650 5450);
FORCEPROP 2 LAST CDS_LIB pure_quanta
J 0
(-3625 5600);
PAINT MONO (-3625 5600);
DISPLAY INVISIBLE (-3625 5600);
FORCEPROP 1 LAST PATH I26
J 0
(-3675 5750);
DISPLAY 0.978723 (-3675 5750);
PAINT WHITE (-3675 5750);
DISPLAY INVISIBLE (-3675 5750);
FORCEPROP 1 LAST PART_NUMBER CS02202FB02
J 0
(-3675 5700);
DISPLAY 0.978723 (-3675 5700);
PAINT SKYBLUE (-3675 5700);
DISPLAY INVISIBLE (-3675 5700);
FORCEADD Q_RES..1
(-3625 5700);
FORCEPROP 1 LAST LOCATION R1638
J 0
(-4000 5700);
DISPLAY 0.489362 (-4000 5700);
PAINT SKYBLUE (-4000 5700);
FORCEPROP 0 LAST $SEC 1
J 0
(-3875 5750);
PAINT MONO (-3875 5750);
DISPLAY INVISIBLE (-3875 5750);
FORCEPROP 0 LAST CDS_SEC 1
J 0
(-3875 5750);
PAINT MONO (-3875 5750);
DISPLAY INVISIBLE (-3875 5750);
FORCEPROP 1 LASTPIN (-3725 5700) $PN 1
J 0
(-3713 5712);
DISPLAY 0.489362 (-3713 5712);
PAINT GREEN (-3713 5712);
FORCEPROP 1 LASTPIN (-3525 5700) $PN 2
J 0
(-3563 5712);
DISPLAY 0.489362 (-3563 5712);
PAINT GREEN (-3563 5712);
FORCEPROP 1 LAST VALUE 22
J 2
(-3725 5700);
DISPLAY 0.489362 (-3725 5700);
PAINT SKYBLUE (-3725 5700);
FORCEPROP 1 LAST TOLERANCE 1%
J 0
(-3525 5675);
DISPLAY 0.489362 (-3525 5675);
PAINT SKYBLUE (-3525 5675);
FORCEPROP 1 LAST MATERIAL CHIP
J 0
(-3800 5675);
DISPLAY 0.489362 (-3800 5675);
PAINT SKYBLUE (-3800 5675);
FORCEPROP 1 LAST PACK_TYPE 0402LF
J 0
(-3375 5550);
DISPLAY 0.978723 (-3375 5550);
PAINT SKYBLUE (-3375 5550);
DISPLAY INVISIBLE (-3375 5550);
FORCEPROP 1 LAST WATTAGE 1/16W
J 2
(-3650 5550);
DISPLAY 0.978723 (-3650 5550);
PAINT SKYBLUE (-3650 5550);
DISPLAY INVISIBLE (-3650 5550);
FORCEPROP 2 LAST CDS_LIB pure_quanta
J 0
(-3625 5700);
PAINT MONO (-3625 5700);
DISPLAY INVISIBLE (-3625 5700);
FORCEPROP 1 LAST PATH I27
J 0
(-3675 5850);
DISPLAY 0.978723 (-3675 5850);
PAINT WHITE (-3675 5850);
DISPLAY INVISIBLE (-3675 5850);
FORCEPROP 1 LAST PART_NUMBER CS02202FB02
J 0
(-3675 5800);
DISPLAY 0.978723 (-3675 5800);
PAINT SKYBLUE (-3675 5800);
DISPLAY INVISIBLE (-3675 5800);
FORCEADD SN74AVC4T774PWR..1
(-5325 3875);
FORCEPROP 1 LAST LOCATION U151
J 0
(-5572 4440);
DISPLAY 0.489362 (-5572 4440);
PAINT SKYBLUE (-5572 4440);
FORCEPROP 0 LAST $SEC 1
J 0
(-5575 4625);
DISPLAY 0.680851 (-5575 4625);
PAINT MONO (-5575 4625);
DISPLAY INVISIBLE (-5575 4625);
FORCEPROP 0 LAST CDS_SEC 1
J 0
(-5575 4625);
DISPLAY 1.021277 (-5575 4625);
DISPLAY INVISIBLE (-5575 4625);
FORCEPROP 0 LASTPIN (-5725 4025) $PN 3
J 2
(-5735 4035);
DISPLAY 0.489362 (-5735 4035);
PAINT MONO (-5735 4035);
FORCEPROP 0 LASTPIN (-5725 3975) $PN 4
J 2
(-5735 3985);
DISPLAY 0.489362 (-5735 3985);
PAINT MONO (-5735 3985);
FORCEPROP 0 LASTPIN (-5725 3925) $PN 5
J 2
(-5735 3935);
DISPLAY 0.489362 (-5735 3935);
PAINT MONO (-5735 3935);
FORCEPROP 0 LASTPIN (-5725 3875) $PN 6
J 2
(-5735 3885);
DISPLAY 0.489362 (-5735 3885);
PAINT MONO (-5735 3885);
FORCEPROP 0 LASTPIN (-4925 4025) $PN 14
J 0
(-4915 4035);
DISPLAY 0.489362 (-4915 4035);
PAINT MONO (-4915 4035);
FORCEPROP 0 LASTPIN (-4925 3975) $PN 13
J 0
(-4915 3985);
DISPLAY 0.489362 (-4915 3985);
PAINT MONO (-4915 3985);
FORCEPROP 0 LASTPIN (-4925 3925) $PN 12
J 0
(-4915 3935);
DISPLAY 0.489362 (-4915 3935);
PAINT MONO (-4915 3935);
FORCEPROP 0 LASTPIN (-4925 3875) $PN 11
J 0
(-4915 3885);
DISPLAY 0.489362 (-4915 3885);
PAINT MONO (-4915 3885);
FORCEPROP 0 LASTPIN (-5725 3725) $PN 1
J 2
(-5735 3735);
DISPLAY 0.489362 (-5735 3735);
PAINT MONO (-5735 3735);
FORCEPROP 0 LASTPIN (-5725 3675) $PN 2
J 2
(-5735 3685);
DISPLAY 0.489362 (-5735 3685);
PAINT MONO (-5735 3685);
FORCEPROP 0 LASTPIN (-5725 3625) $PN 7
J 2
(-5735 3635);
DISPLAY 0.489362 (-5735 3635);
PAINT MONO (-5735 3635);
FORCEPROP 0 LASTPIN (-5725 3575) $PN 8
J 2
(-5735 3585);
DISPLAY 0.489362 (-5735 3585);
PAINT MONO (-5735 3585);
FORCEPROP 0 LASTPIN (-4925 3475) $PN 10
J 0
(-4915 3485);
DISPLAY 0.489362 (-4915 3485);
PAINT MONO (-4915 3485);
FORCEPROP 0 LASTPIN (-5725 3525) $PN 9
J 2
(-5735 3535);
DISPLAY 0.489362 (-5735 3535);
PAINT MONO (-5735 3535);
FORCEPROP 0 LASTPIN (-5725 4225) $PN 16
J 2
(-5735 4235);
DISPLAY 0.489362 (-5735 4235);
PAINT MONO (-5735 4235);
FORCEPROP 0 LASTPIN (-4925 4225) $PN 15
J 0
(-4915 4235);
DISPLAY 0.489362 (-4915 4235);
PAINT MONO (-4915 4235);
FORCEPROP 2 LAST VALUE SN74AVC4T774PWR
J 0
(-5575 4500);
DISPLAY 0.489362 (-5575 4500);
PAINT SKYBLUE (-5575 4500);
FORCEPROP 1 LAST MATERIAL IC
J 0
(-5572 4328);
DISPLAY 0.489362 (-5572 4328);
PAINT SKYBLUE (-5572 4328);
FORCEPROP 2 LAST PART_TYPE SMLF
J 0
(-5575 4575);
PAINT MONO (-5575 4575);
FORCEPROP 1 LAST NEEDS_NO_SIZE TRUE
J 0
(-5325 3875);
DISPLAY 0.723404 (-5325 3875);
PAINT GREEN (-5325 3875);
DISPLAY INVISIBLE (-5325 3875);
FORCEPROP 1 LAST CDS_LMAN_SYM_OUTLINE -250,450,250,-450
J 0
(-5325 3875);
DISPLAY 0.468085 (-5325 3875);
PAINT GREEN (-5325 3875);
DISPLAY INVISIBLE (-5325 3875);
FORCEPROP 2 LAST CDS_LIB pure_quanta
J 0
(-5325 3875);
DISPLAY INVISIBLE (-5325 3875);
FORCEPROP 1 LAST PATH I28
J 0
(-5325 3875);
DISPLAY 0.723404 (-5325 3875);
PAINT GREEN (-5325 3875);
DISPLAY INVISIBLE (-5325 3875);
FORCEPROP 1 LAST PART_NUMBER AL04T774K00
J 0
(-5572 4383);
DISPLAY 0.489362 (-5572 4383);
PAINT SKYBLUE (-5572 4383);
DISPLAY INVISIBLE (-5572 4383);
FORCEADD OFFPAGE..2
(-2325 3925);
FORCEPROP 2 LAST $XR0 54 
J 0
(-2136 3925);
DISPLAY 0.638298 (-2136 3925);
PAINT MONO (-2136 3925);
FORCEPROP 2 LAST CDS_LIB standard
J 0
(-2325 3925);
PAINT MONO (-2325 3925);
DISPLAY INVISIBLE (-2325 3925);
FORCEPROP 1 LAST OFFPAGE TRUE
J 0
(-2000 3800);
DISPLAY 0.872340 (-2000 3800);
PAINT GREEN (-2000 3800);
DISPLAY INVISIBLE (-2000 3800);
FORCEPROP 1 LAST COMMENT_BODY TRUE
J 0
(-2370 3830);
DISPLAY 0.872340 (-2370 3830);
PAINT GREEN (-2370 3830);
DISPLAY INVISIBLE (-2370 3830);
FORCEPROP 2 LAST PATH I29
J 0
(-2125 3975);
DISPLAY 1.021277 (-2125 3975);
DISPLAY INVISIBLE (-2125 3975);
FORCEADD OFFPAGE..2
(-2325 3975);
FORCEPROP 2 LAST $XR0 54 
J 0
(-2136 3975);
DISPLAY 0.638298 (-2136 3975);
PAINT MONO (-2136 3975);
FORCEPROP 2 LAST CDS_LIB standard
J 0
(-2325 3975);
PAINT MONO (-2325 3975);
DISPLAY INVISIBLE (-2325 3975);
FORCEPROP 1 LAST OFFPAGE TRUE
J 0
(-2000 3850);
DISPLAY 0.872340 (-2000 3850);
PAINT GREEN (-2000 3850);
DISPLAY INVISIBLE (-2000 3850);
FORCEPROP 1 LAST COMMENT_BODY TRUE
J 0
(-2370 3880);
DISPLAY 0.872340 (-2370 3880);
PAINT GREEN (-2370 3880);
DISPLAY INVISIBLE (-2370 3880);
FORCEPROP 2 LAST PATH I30
J 0
(-2125 4025);
DISPLAY 1.021277 (-2125 4025);
DISPLAY INVISIBLE (-2125 4025);
FORCEADD OFFPAGE..2
(-2325 4025);
FORCEPROP 2 LAST $XR0 54 
J 0
(-2136 4025);
DISPLAY 0.638298 (-2136 4025);
PAINT MONO (-2136 4025);
FORCEPROP 2 LAST CDS_LIB standard
J 0
(-2325 4025);
PAINT MONO (-2325 4025);
DISPLAY INVISIBLE (-2325 4025);
FORCEPROP 1 LAST OFFPAGE TRUE
J 0
(-2000 3900);
DISPLAY 0.872340 (-2000 3900);
PAINT GREEN (-2000 3900);
DISPLAY INVISIBLE (-2000 3900);
FORCEPROP 1 LAST COMMENT_BODY TRUE
J 0
(-2370 3930);
DISPLAY 0.872340 (-2370 3930);
PAINT GREEN (-2370 3930);
DISPLAY INVISIBLE (-2370 3930);
FORCEPROP 2 LAST PATH I31
J 0
(-2125 4075);
DISPLAY 1.021277 (-2125 4075);
DISPLAY INVISIBLE (-2125 4075);
FORCEADD OFFPAGE..2
(-2325 3875);
FORCEPROP 2 LAST $XR0 54 
J 0
(-2136 3875);
DISPLAY 0.638298 (-2136 3875);
PAINT MONO (-2136 3875);
FORCEPROP 2 LAST CDS_LIB standard
J 0
(-2325 3875);
PAINT MONO (-2325 3875);
DISPLAY INVISIBLE (-2325 3875);
FORCEPROP 1 LAST OFFPAGE TRUE
J 0
(-2000 3750);
DISPLAY 0.872340 (-2000 3750);
PAINT GREEN (-2000 3750);
DISPLAY INVISIBLE (-2000 3750);
FORCEPROP 1 LAST COMMENT_BODY TRUE
J 0
(-2370 3780);
DISPLAY 0.872340 (-2370 3780);
PAINT GREEN (-2370 3780);
DISPLAY INVISIBLE (-2370 3780);
FORCEPROP 2 LAST PATH I32
J 0
(-2125 3925);
DISPLAY 1.021277 (-2125 3925);
DISPLAY INVISIBLE (-2125 3925);
FORCEADD Q_RES..1
(-3625 4025);
FORCEPROP 1 LAST LOCATION R1642
J 0
(-4000 4025);
DISPLAY 0.489362 (-4000 4025);
PAINT SKYBLUE (-4000 4025);
FORCEPROP 0 LAST $SEC 1
J 0
(-3875 4075);
PAINT MONO (-3875 4075);
DISPLAY INVISIBLE (-3875 4075);
FORCEPROP 0 LAST CDS_SEC 1
J 0
(-3875 4075);
PAINT MONO (-3875 4075);
DISPLAY INVISIBLE (-3875 4075);
FORCEPROP 1 LASTPIN (-3725 4025) $PN 1
J 0
(-3713 4037);
DISPLAY 0.489362 (-3713 4037);
PAINT GREEN (-3713 4037);
FORCEPROP 1 LASTPIN (-3525 4025) $PN 2
J 0
(-3563 4037);
DISPLAY 0.489362 (-3563 4037);
PAINT GREEN (-3563 4037);
FORCEPROP 1 LAST VALUE 22
J 2
(-3725 4025);
DISPLAY 0.489362 (-3725 4025);
PAINT SKYBLUE (-3725 4025);
FORCEPROP 1 LAST TOLERANCE 1%
J 0
(-3525 4000);
DISPLAY 0.489362 (-3525 4000);
PAINT SKYBLUE (-3525 4000);
FORCEPROP 1 LAST MATERIAL CHIP
J 0
(-3800 4000);
DISPLAY 0.489362 (-3800 4000);
PAINT SKYBLUE (-3800 4000);
FORCEPROP 1 LAST PACK_TYPE 0402LF
J 0
(-3375 3875);
DISPLAY 0.978723 (-3375 3875);
PAINT SKYBLUE (-3375 3875);
DISPLAY INVISIBLE (-3375 3875);
FORCEPROP 1 LAST WATTAGE 1/16W
J 2
(-3650 3875);
DISPLAY 0.978723 (-3650 3875);
PAINT SKYBLUE (-3650 3875);
DISPLAY INVISIBLE (-3650 3875);
FORCEPROP 2 LAST CDS_LIB pure_quanta
J 0
(-3625 4025);
PAINT MONO (-3625 4025);
DISPLAY INVISIBLE (-3625 4025);
FORCEPROP 1 LAST PATH I33
J 0
(-3675 4175);
DISPLAY 0.978723 (-3675 4175);
PAINT WHITE (-3675 4175);
DISPLAY INVISIBLE (-3675 4175);
FORCEPROP 1 LAST PART_NUMBER CS02202FB02
J 0
(-3675 4125);
DISPLAY 0.978723 (-3675 4125);
PAINT SKYBLUE (-3675 4125);
DISPLAY INVISIBLE (-3675 4125);
FORCEADD Q_RES..1
(-3625 3975);
FORCEPROP 1 LAST LOCATION R1643
J 0
(-4000 3975);
DISPLAY 0.489362 (-4000 3975);
PAINT SKYBLUE (-4000 3975);
FORCEPROP 0 LAST $SEC 1
J 0
(-3950 4025);
DISPLAY 0.680851 (-3950 4025);
PAINT MONO (-3950 4025);
DISPLAY INVISIBLE (-3950 4025);
FORCEPROP 0 LAST CDS_SEC 1
J 0
(-3950 4025);
DISPLAY 1.021277 (-3950 4025);
DISPLAY INVISIBLE (-3950 4025);
FORCEPROP 1 LASTPIN (-3725 3975) $PN 1
J 0
(-3713 3987);
DISPLAY 0.489362 (-3713 3987);
PAINT MONO (-3713 3987);
FORCEPROP 1 LASTPIN (-3525 3975) $PN 2
J 0
(-3563 3987);
DISPLAY 0.489362 (-3563 3987);
PAINT MONO (-3563 3987);
FORCEPROP 1 LAST VALUE 22
J 2
(-3725 3975);
DISPLAY 0.489362 (-3725 3975);
PAINT SKYBLUE (-3725 3975);
FORCEPROP 1 LAST TOLERANCE 1%
J 0
(-3525 3950);
DISPLAY 0.489362 (-3525 3950);
PAINT SKYBLUE (-3525 3950);
FORCEPROP 1 LAST MATERIAL CHIP
J 0
(-3800 3950);
DISPLAY 0.489362 (-3800 3950);
PAINT SKYBLUE (-3800 3950);
FORCEPROP 1 LAST PACK_TYPE 0402LF
J 0
(-3375 3825);
DISPLAY 0.978723 (-3375 3825);
PAINT SKYBLUE (-3375 3825);
DISPLAY INVISIBLE (-3375 3825);
FORCEPROP 1 LAST WATTAGE 1/16W
J 2
(-3650 3825);
DISPLAY 0.978723 (-3650 3825);
PAINT SKYBLUE (-3650 3825);
DISPLAY INVISIBLE (-3650 3825);
FORCEPROP 2 LAST CDS_LIB pure_quanta
J 0
(-3625 3975);
DISPLAY INVISIBLE (-3625 3975);
FORCEPROP 1 LAST PATH I34
J 0
(-3675 4125);
DISPLAY 0.978723 (-3675 4125);
PAINT WHITE (-3675 4125);
DISPLAY INVISIBLE (-3675 4125);
FORCEPROP 1 LAST PART_NUMBER CS02202FB02
J 0
(-3675 4075);
DISPLAY 0.978723 (-3675 4075);
PAINT SKYBLUE (-3675 4075);
DISPLAY INVISIBLE (-3675 4075);
FORCEADD Q_RES..1
(-3625 3925);
FORCEPROP 1 LAST LOCATION R1644
J 0
(-4000 3925);
DISPLAY 0.489362 (-4000 3925);
PAINT SKYBLUE (-4000 3925);
FORCEPROP 0 LAST $SEC 1
J 0
(-3875 3975);
PAINT MONO (-3875 3975);
DISPLAY INVISIBLE (-3875 3975);
FORCEPROP 0 LAST CDS_SEC 1
J 0
(-3875 3975);
PAINT MONO (-3875 3975);
DISPLAY INVISIBLE (-3875 3975);
FORCEPROP 1 LASTPIN (-3725 3925) $PN 1
J 0
(-3713 3937);
DISPLAY 0.489362 (-3713 3937);
PAINT GREEN (-3713 3937);
FORCEPROP 1 LASTPIN (-3525 3925) $PN 2
J 0
(-3563 3937);
DISPLAY 0.489362 (-3563 3937);
PAINT GREEN (-3563 3937);
FORCEPROP 1 LAST VALUE 22
J 2
(-3725 3925);
DISPLAY 0.489362 (-3725 3925);
PAINT SKYBLUE (-3725 3925);
FORCEPROP 1 LAST TOLERANCE 1%
J 0
(-3525 3900);
DISPLAY 0.489362 (-3525 3900);
PAINT SKYBLUE (-3525 3900);
FORCEPROP 1 LAST MATERIAL CHIP
J 0
(-3800 3900);
DISPLAY 0.489362 (-3800 3900);
PAINT SKYBLUE (-3800 3900);
FORCEPROP 1 LAST PACK_TYPE 0402LF
J 0
(-3375 3775);
DISPLAY 0.978723 (-3375 3775);
PAINT SKYBLUE (-3375 3775);
DISPLAY INVISIBLE (-3375 3775);
FORCEPROP 1 LAST WATTAGE 1/16W
J 2
(-3650 3775);
DISPLAY 0.978723 (-3650 3775);
PAINT SKYBLUE (-3650 3775);
DISPLAY INVISIBLE (-3650 3775);
FORCEPROP 2 LAST CDS_LIB pure_quanta
J 0
(-3625 3925);
PAINT MONO (-3625 3925);
DISPLAY INVISIBLE (-3625 3925);
FORCEPROP 1 LAST PATH I35
J 0
(-3675 4075);
DISPLAY 0.978723 (-3675 4075);
PAINT WHITE (-3675 4075);
DISPLAY INVISIBLE (-3675 4075);
FORCEPROP 1 LAST PART_NUMBER CS02202FB02
J 0
(-3675 4025);
DISPLAY 0.978723 (-3675 4025);
PAINT SKYBLUE (-3675 4025);
DISPLAY INVISIBLE (-3675 4025);
FORCEADD Q_RES..1
(-3625 3875);
FORCEPROP 1 LAST LOCATION R1645
J 0
(-4000 3875);
DISPLAY 0.489362 (-4000 3875);
PAINT SKYBLUE (-4000 3875);
FORCEPROP 0 LAST $SEC 1
J 0
(-3875 3925);
PAINT MONO (-3875 3925);
DISPLAY INVISIBLE (-3875 3925);
FORCEPROP 0 LAST CDS_SEC 1
J 0
(-3875 3925);
PAINT MONO (-3875 3925);
DISPLAY INVISIBLE (-3875 3925);
FORCEPROP 1 LASTPIN (-3725 3875) $PN 1
J 0
(-3713 3887);
DISPLAY 0.489362 (-3713 3887);
PAINT GREEN (-3713 3887);
FORCEPROP 1 LASTPIN (-3525 3875) $PN 2
J 0
(-3563 3887);
DISPLAY 0.489362 (-3563 3887);
PAINT GREEN (-3563 3887);
FORCEPROP 1 LAST VALUE 22
J 2
(-3725 3875);
DISPLAY 0.489362 (-3725 3875);
PAINT SKYBLUE (-3725 3875);
FORCEPROP 1 LAST TOLERANCE 1%
J 0
(-3525 3850);
DISPLAY 0.489362 (-3525 3850);
PAINT SKYBLUE (-3525 3850);
FORCEPROP 1 LAST MATERIAL CHIP
J 0
(-3800 3850);
DISPLAY 0.489362 (-3800 3850);
PAINT SKYBLUE (-3800 3850);
FORCEPROP 1 LAST PACK_TYPE 0402LF
J 0
(-3375 3725);
DISPLAY 0.978723 (-3375 3725);
PAINT SKYBLUE (-3375 3725);
DISPLAY INVISIBLE (-3375 3725);
FORCEPROP 1 LAST WATTAGE 1/16W
J 2
(-3650 3725);
DISPLAY 0.978723 (-3650 3725);
PAINT SKYBLUE (-3650 3725);
DISPLAY INVISIBLE (-3650 3725);
FORCEPROP 2 LAST CDS_LIB pure_quanta
J 0
(-3625 3875);
PAINT MONO (-3625 3875);
DISPLAY INVISIBLE (-3625 3875);
FORCEPROP 1 LAST PATH I36
J 0
(-3675 4025);
DISPLAY 0.978723 (-3675 4025);
PAINT WHITE (-3675 4025);
DISPLAY INVISIBLE (-3675 4025);
FORCEPROP 1 LAST PART_NUMBER CS02202FB02
J 0
(-3675 3975);
DISPLAY 0.978723 (-3675 3975);
PAINT SKYBLUE (-3675 3975);
DISPLAY INVISIBLE (-3675 3975);
FORCEADD UNIVERSAL_POWER..1
(-4800 4725);
FORCEPROP 3 LASTPIN (-4800 4675) SIG_NAME PVDD18_S5_P1\g
J 0
(-4790 4685);
DISPLAY 0.659574 (-4790 4685);
PAINT MONO (-4790 4685);
DISPLAY INVISIBLE (-4790 4685);
FORCEPROP 1 LAST HDL_POWER PVDD18_S5_P1
J 1
(-4800 4775);
DISPLAY 0.489362 (-4800 4775);
PAINT GREEN (-4800 4775);
FORCEPROP 2 LAST CDS_LIB pure_quanta_power
J 0
(-4800 4725);
PAINT MONO (-4800 4725);
DISPLAY INVISIBLE (-4800 4725);
FORCEPROP 1 LAST PATH I37
J 0
(-4750 4750);
DISPLAY 0.872340 (-4750 4750);
PAINT AQUA (-4750 4750);
DISPLAY INVISIBLE (-4750 4750);
FORCEADD UNIVERSAL_POWER..1
(-5850 4725);
FORCEPROP 3 LASTPIN (-5850 4675) SIG_NAME PVDD18_S5_P0\g
J 0
(-5840 4685);
DISPLAY 0.659574 (-5840 4685);
PAINT MONO (-5840 4685);
DISPLAY INVISIBLE (-5840 4685);
FORCEPROP 1 LAST HDL_POWER PVDD18_S5_P0
J 1
(-5850 4775);
DISPLAY 0.489362 (-5850 4775);
PAINT GREEN (-5850 4775);
FORCEPROP 2 LAST CDS_LIB pure_quanta_power
J 0
(-5850 4725);
PAINT MONO (-5850 4725);
DISPLAY INVISIBLE (-5850 4725);
FORCEPROP 1 LAST PATH I38
J 0
(-5800 4750);
DISPLAY 0.872340 (-5800 4750);
PAINT AQUA (-5800 4750);
DISPLAY INVISIBLE (-5800 4750);
FORCEADD GND..1
(-4650 4175);
FORCEPROP 3 LASTPIN (-4650 4225) SIG_NAME GND\g
J 0
(-4640 4235);
DISPLAY 0.659574 (-4640 4235);
PAINT MONO (-4640 4235);
DISPLAY INVISIBLE (-4640 4235);
FORCEPROP 2 LAST CDS_LIB pure_quanta_power
J 0
(-4650 4175);
DISPLAY INVISIBLE (-4650 4175);
FORCEPROP 1 LAST SIZE 1B
J 0
(-4575 4125);
DISPLAY 0.872340 (-4575 4125);
PAINT GREEN (-4575 4125);
DISPLAY INVISIBLE (-4575 4125);
FORCEPROP 1 LAST HDL_POWER GND
J 0
(-4650 4325);
DISPLAY 0.872340 (-4650 4325);
PAINT GREEN (-4650 4325);
DISPLAY INVISIBLE (-4650 4325);
FORCEPROP 1 LAST PATH I39
J 0
(-4575 4175);
DISPLAY 0.872340 (-4575 4175);
PAINT AQUA (-4575 4175);
DISPLAY INVISIBLE (-4575 4175);
FORCEADD Q_CAP..1
(-4650 4400);
FORCEPROP 1 LAST LOCATION C1517
J 0
(-4550 4550);
DISPLAY 0.489362 (-4550 4550);
PAINT SKYBLUE (-4550 4550);
FORCEPROP 2 LAST $SEC 1
J 0
(-4600 4600);
PAINT MONO (-4600 4600);
DISPLAY INVISIBLE (-4600 4600);
FORCEPROP 2 LAST CDS_SEC 1
J 0
(-4600 4600);
PAINT MONO (-4600 4600);
DISPLAY INVISIBLE (-4600 4600);
FORCEPROP 1 LASTPIN (-4650 4500) $PN 1
J 0
(-4640 4480);
DISPLAY 0.489362 (-4640 4480);
PAINT GREEN (-4640 4480);
FORCEPROP 1 LASTPIN (-4650 4300) $PN 2
J 0
(-4640 4280);
DISPLAY 0.489362 (-4640 4280);
PAINT GREEN (-4640 4280);
FORCEPROP 1 LAST MATERIAL X7R
J 0
(-4550 4350);
DISPLAY 0.489362 (-4550 4350);
PAINT SKYBLUE (-4550 4350);
FORCEPROP 1 LAST TOLERANCE 10%
J 0
(-4550 4400);
DISPLAY 0.489362 (-4550 4400);
PAINT SKYBLUE (-4550 4400);
FORCEPROP 1 LAST VOLTAGE 16V
J 0
(-4550 4450);
DISPLAY 0.489362 (-4550 4450);
PAINT SKYBLUE (-4550 4450);
FORCEPROP 1 LAST VALUE 0.1UF
J 0
(-4550 4500);
DISPLAY 0.489362 (-4550 4500);
PAINT SKYBLUE (-4550 4500);
FORCEPROP 1 LAST PACK_TYPE C0402
J 0
(-4550 4250);
DISPLAY 0.489362 (-4550 4250);
PAINT SKYBLUE (-4550 4250);
FORCEPROP 2 LAST CDS_LIB pure_quanta
J 0
(-4650 4400);
DISPLAY INVISIBLE (-4650 4400);
FORCEPROP 1 LAST PATH I40
J 0
(-4600 4550);
DISPLAY 0.978723 (-4600 4550);
PAINT WHITE (-4600 4550);
DISPLAY INVISIBLE (-4600 4550);
FORCEPROP 1 LAST PART_NUMBER CH4103K1B08
J 0
(-4550 4300);
DISPLAY 0.489362 (-4550 4300);
PAINT SKYBLUE (-4550 4300);
DISPLAY INVISIBLE (-4550 4300);
FORCEADD GND..1
(-4800 3350);
FORCEPROP 3 LASTPIN (-4800 3400) SIG_NAME GND\g
J 0
(-4790 3410);
DISPLAY 0.659574 (-4790 3410);
PAINT MONO (-4790 3410);
DISPLAY INVISIBLE (-4790 3410);
FORCEPROP 1 LAST SIZE 1B
J 0
(-4725 3300);
DISPLAY 0.872340 (-4725 3300);
PAINT GREEN (-4725 3300);
DISPLAY INVISIBLE (-4725 3300);
FORCEPROP 2 LAST CDS_LIB pure_quanta_power
J 0
(-4800 3350);
PAINT MONO (-4800 3350);
DISPLAY INVISIBLE (-4800 3350);
FORCEPROP 1 LAST HDL_POWER GND
J 0
(-4800 3500);
DISPLAY 0.872340 (-4800 3500);
PAINT GREEN (-4800 3500);
DISPLAY INVISIBLE (-4800 3500);
FORCEPROP 1 LAST PATH I41
J 0
(-4725 3350);
DISPLAY 0.872340 (-4725 3350);
PAINT AQUA (-4725 3350);
DISPLAY INVISIBLE (-4725 3350);
FORCEADD GND..1
(-6050 4225);
FORCEPROP 3 LASTPIN (-6050 4275) SIG_NAME GND\g
J 0
(-6040 4285);
DISPLAY 0.659574 (-6040 4285);
PAINT MONO (-6040 4285);
DISPLAY INVISIBLE (-6040 4285);
FORCEPROP 2 LAST CDS_LIB pure_quanta_power
J 0
(-6050 4225);
DISPLAY INVISIBLE (-6050 4225);
FORCEPROP 1 LAST SIZE 1B
J 0
(-5975 4175);
DISPLAY 0.872340 (-5975 4175);
PAINT GREEN (-5975 4175);
DISPLAY INVISIBLE (-5975 4175);
FORCEPROP 1 LAST HDL_POWER GND
J 0
(-6050 4375);
DISPLAY 0.872340 (-6050 4375);
PAINT GREEN (-6050 4375);
DISPLAY INVISIBLE (-6050 4375);
FORCEPROP 1 LAST PATH I42
J 0
(-5975 4225);
DISPLAY 0.872340 (-5975 4225);
PAINT AQUA (-5975 4225);
DISPLAY INVISIBLE (-5975 4225);
FORCEADD Q_CAP..1
(-6050 4450);
FORCEPROP 1 LAST LOCATION C1515
J 0
(-6200 4575);
DISPLAY 0.489362 (-6200 4575);
PAINT SKYBLUE (-6200 4575);
FORCEPROP 2 LAST $SEC 1
J 0
(-6000 4650);
PAINT MONO (-6000 4650);
DISPLAY INVISIBLE (-6000 4650);
FORCEPROP 2 LAST CDS_SEC 1
J 0
(-6000 4650);
PAINT MONO (-6000 4650);
DISPLAY INVISIBLE (-6000 4650);
FORCEPROP 1 LASTPIN (-6050 4550) $PN 1
J 0
(-6040 4530);
DISPLAY 0.489362 (-6040 4530);
PAINT GREEN (-6040 4530);
FORCEPROP 1 LASTPIN (-6050 4350) $PN 2
J 0
(-6040 4330);
DISPLAY 0.489362 (-6040 4330);
PAINT GREEN (-6040 4330);
FORCEPROP 1 LAST TOLERANCE 10%
J 0
(-6175 4425);
DISPLAY 0.489362 (-6175 4425);
PAINT SKYBLUE (-6175 4425);
FORCEPROP 1 LAST VOLTAGE 16V
J 0
(-6175 4475);
DISPLAY 0.489362 (-6175 4475);
PAINT SKYBLUE (-6175 4475);
FORCEPROP 1 LAST MATERIAL X7R
J 0
(-6175 4375);
DISPLAY 0.489362 (-6175 4375);
PAINT SKYBLUE (-6175 4375);
FORCEPROP 1 LAST VALUE 0.1UF
J 0
(-6225 4525);
DISPLAY 0.489362 (-6225 4525);
PAINT SKYBLUE (-6225 4525);
FORCEPROP 1 LAST PACK_TYPE C0402
J 0
(-6225 4275);
DISPLAY 0.489362 (-6225 4275);
PAINT SKYBLUE (-6225 4275);
FORCEPROP 2 LAST CDS_LIB pure_quanta
J 0
(-6050 4450);
DISPLAY INVISIBLE (-6050 4450);
FORCEPROP 1 LAST PATH I43
J 0
(-6000 4600);
DISPLAY 0.978723 (-6000 4600);
PAINT WHITE (-6000 4600);
DISPLAY INVISIBLE (-6000 4600);
FORCEPROP 1 LAST PART_NUMBER CH4103K1B08
J 0
(-6400 4325);
DISPLAY 0.489362 (-6400 4325);
PAINT SKYBLUE (-6400 4325);
DISPLAY INVISIBLE (-6400 4325);
FORCEADD SN74AVC2T245RSWR..1
R 2
(-5325 2175);
FORCEPROP 1 LAST LOCATION U152
J 2
(-5080 2715);
DISPLAY 0.489362 (-5080 2715);
PAINT SKYBLUE (-5080 2715);
FORCEPROP 0 LAST $SEC 1
J 0
(-5075 2875);
DISPLAY 0.680851 (-5075 2875);
PAINT MONO (-5075 2875);
DISPLAY INVISIBLE (-5075 2875);
FORCEPROP 0 LAST CDS_SEC 1
J 0
(-5075 2875);
DISPLAY 1.021277 (-5075 2875);
DISPLAY INVISIBLE (-5075 2875);
FORCEPROP 0 LASTPIN (-5725 2300) $PN 8
J 2
(-5735 2310);
DISPLAY 0.489362 (-5735 2310);
PAINT MONO (-5735 2310);
FORCEPROP 0 LASTPIN (-5725 2150) $PN 9
J 2
(-5735 2160);
DISPLAY 0.489362 (-5735 2160);
PAINT MONO (-5735 2160);
FORCEPROP 0 LASTPIN (-4925 2250) $PN 5
J 0
(-4915 2260);
DISPLAY 0.489362 (-4915 2260);
PAINT MONO (-4915 2260);
FORCEPROP 0 LASTPIN (-4925 2100) $PN 4
J 0
(-4915 2110);
DISPLAY 0.489362 (-4915 2110);
PAINT MONO (-4915 2110);
FORCEPROP 0 LASTPIN (-5725 2250) $PN 10
J 2
(-5735 2260);
DISPLAY 0.489362 (-5735 2260);
PAINT MONO (-5735 2260);
FORCEPROP 0 LASTPIN (-5725 2100) $PN 1
J 2
(-5735 2110);
DISPLAY 0.489362 (-5735 2110);
PAINT MONO (-5735 2110);
FORCEPROP 0 LASTPIN (-5725 1850) $PN 3
J 2
(-5735 1860);
DISPLAY 0.489362 (-5735 1860);
PAINT MONO (-5735 1860);
FORCEPROP 0 LASTPIN (-5725 2000) $PN 2
J 2
(-5735 2010);
DISPLAY 0.489362 (-5735 2010);
PAINT MONO (-5735 2010);
FORCEPROP 0 LASTPIN (-4925 2500) $PN 7
J 0
(-4915 2510);
DISPLAY 0.489362 (-4915 2510);
PAINT MONO (-4915 2510);
FORCEPROP 0 LASTPIN (-4925 2450) $PN 6
J 0
(-4915 2460);
DISPLAY 0.489362 (-4915 2460);
PAINT MONO (-4915 2460);
FORCEPROP 1 LAST MATERIAL IC
J 2
(-5080 2557);
DISPLAY 0.489362 (-5080 2557);
PAINT SKYBLUE (-5080 2557);
FORCEPROP 2 LAST VALUE SN74AVC2T245RSWR
J 2
(-5075 2775);
DISPLAY 0.489362 (-5075 2775);
PAINT SKYBLUE (-5075 2775);
FORCEPROP 2 LAST PART_TYPE SMLF
J 2
(-5075 2825);
PAINT MONO (-5075 2825);
FORCEPROP 2 LAST CDS_LIB pure_quanta
J 0
(-5325 2175);
DISPLAY INVISIBLE (-5325 2175);
FORCEPROP 1 LAST CDS_LMAN_SYM_OUTLINE -250,375,250,-375
J 2
(-5325 2175);
DISPLAY 0.468085 (-5325 2175);
PAINT GREEN (-5325 2175);
DISPLAY INVISIBLE (-5325 2175);
FORCEPROP 1 LAST NEEDS_NO_SIZE TRUE
J 2
(-5575 1857);
DISPLAY 0.723404 (-5575 1857);
PAINT GREEN (-5575 1857);
DISPLAY INVISIBLE (-5575 1857);
FORCEPROP 1 LAST PATH I60
J 2
(-5575 1800);
DISPLAY 0.723404 (-5575 1800);
PAINT GREEN (-5575 1800);
DISPLAY INVISIBLE (-5575 1800);
FORCEPROP 1 LAST PART_NUMBER AL02T245000
J 2
(-5080 2626);
DISPLAY 0.489362 (-5080 2626);
PAINT SKYBLUE (-5080 2626);
DISPLAY INVISIBLE (-5080 2626);
FORCEADD OFFPAGE..1
(-6700 2300);
FORCEPROP 2 LAST $XR0 172 
J 0
(-6982 2300);
DISPLAY 0.638298 (-6982 2300);
PAINT MONO (-6982 2300);
FORCEPROP 2 LAST CDS_LIB standard
J 2
(-6700 2300);
DISPLAY INVISIBLE (-6700 2300);
FORCEPROP 1 LAST OFFPAGE TRUE
J 0
(-6375 2175);
DISPLAY 0.872340 (-6375 2175);
PAINT GREEN (-6375 2175);
DISPLAY INVISIBLE (-6375 2175);
FORCEPROP 1 LAST COMMENT_BODY TRUE
J 0
(-6575 2200);
DISPLAY 0.872340 (-6575 2200);
PAINT GREEN (-6575 2200);
DISPLAY INVISIBLE (-6575 2200);
FORCEPROP 2 LAST PATH I61
J 0
(-6650 2375);
DISPLAY 1.021277 (-6650 2375);
DISPLAY INVISIBLE (-6650 2375);
FORCEADD OFFPAGE..2
R 2
(-7250 2150);
FORCEPROP 2 LAST $XR0 172 
J 0
(-7505 2150);
DISPLAY 0.638298 (-7505 2150);
PAINT MONO (-7505 2150);
FORCEPROP 2 LAST CDS_LIB standard
J 2
(-7250 2150);
DISPLAY INVISIBLE (-7250 2150);
FORCEPROP 1 LAST OFFPAGE TRUE
J 2
(-7575 2025);
DISPLAY 0.872340 (-7575 2025);
PAINT GREEN (-7575 2025);
DISPLAY INVISIBLE (-7575 2025);
FORCEPROP 1 LAST COMMENT_BODY TRUE
J 2
(-7205 2055);
DISPLAY 0.872340 (-7205 2055);
PAINT GREEN (-7205 2055);
DISPLAY INVISIBLE (-7205 2055);
FORCEPROP 2 LAST PATH I62
J 2
(-7425 2225);
DISPLAY 1.021277 (-7425 2225);
DISPLAY INVISIBLE (-7425 2225);
FORCEADD GND..1
(-6025 1750);
FORCEPROP 3 LASTPIN (-6025 1800) SIG_NAME GND\g
J 0
(-6015 1810);
DISPLAY 0.659574 (-6015 1810);
PAINT MONO (-6015 1810);
DISPLAY INVISIBLE (-6015 1810);
FORCEPROP 1 LAST SIZE 1B
J 0
(-5950 1700);
DISPLAY 0.872340 (-5950 1700);
PAINT GREEN (-5950 1700);
DISPLAY INVISIBLE (-5950 1700);
FORCEPROP 2 LAST CDS_LIB pure_quanta_power
J 0
(-6025 1750);
PAINT MONO (-6025 1750);
DISPLAY INVISIBLE (-6025 1750);
FORCEPROP 1 LAST HDL_POWER GND
J 0
(-6025 1900);
DISPLAY 0.872340 (-6025 1900);
PAINT GREEN (-6025 1900);
DISPLAY INVISIBLE (-6025 1900);
FORCEPROP 1 LAST PATH I63
J 0
(-5950 1750);
DISPLAY 0.872340 (-5950 1750);
PAINT AQUA (-5950 1750);
DISPLAY INVISIBLE (-5950 1750);
FORCEADD UNIVERSAL_POWER..1
(-4775 2975);
FORCEPROP 3 LASTPIN (-4775 2925) SIG_NAME PVDD18_S5_P0\g
J 0
(-4765 2935);
DISPLAY 0.659574 (-4765 2935);
PAINT MONO (-4765 2935);
DISPLAY INVISIBLE (-4765 2935);
FORCEPROP 1 LAST HDL_POWER PVDD18_S5_P0
J 1
(-4750 3025);
DISPLAY 0.489362 (-4750 3025);
PAINT GREEN (-4750 3025);
FORCEPROP 2 LAST CDS_LIB pure_quanta_power
J 0
(-4775 2975);
PAINT MONO (-4775 2975);
DISPLAY INVISIBLE (-4775 2975);
FORCEPROP 1 LAST PATH I64
J 0
(-4725 3000);
DISPLAY 0.872340 (-4725 3000);
PAINT AQUA (-4725 3000);
DISPLAY INVISIBLE (-4725 3000);
FORCEADD GND..1
(-4650 2475);
FORCEPROP 3 LASTPIN (-4650 2525) SIG_NAME GND\g
J 0
(-4640 2535);
DISPLAY 0.659574 (-4640 2535);
PAINT MONO (-4640 2535);
DISPLAY INVISIBLE (-4640 2535);
FORCEPROP 2 LAST CDS_LIB pure_quanta_power
J 0
(-4650 2475);
DISPLAY INVISIBLE (-4650 2475);
FORCEPROP 1 LAST SIZE 1B
J 0
(-4575 2425);
DISPLAY 0.872340 (-4575 2425);
PAINT GREEN (-4575 2425);
DISPLAY INVISIBLE (-4575 2425);
FORCEPROP 1 LAST HDL_POWER GND
J 0
(-4650 2625);
DISPLAY 0.872340 (-4650 2625);
PAINT GREEN (-4650 2625);
DISPLAY INVISIBLE (-4650 2625);
FORCEPROP 1 LAST PATH I65
J 0
(-4575 2475);
DISPLAY 0.872340 (-4575 2475);
PAINT AQUA (-4575 2475);
DISPLAY INVISIBLE (-4575 2475);
FORCEADD Q_CAP..1
(-4650 2700);
FORCEPROP 1 LAST LOCATION C1518
J 0
(-4550 2850);
DISPLAY 0.489362 (-4550 2850);
PAINT SKYBLUE (-4550 2850);
FORCEPROP 2 LAST $SEC 1
J 0
(-4600 2900);
PAINT MONO (-4600 2900);
DISPLAY INVISIBLE (-4600 2900);
FORCEPROP 2 LAST CDS_SEC 1
J 0
(-4600 2900);
PAINT MONO (-4600 2900);
DISPLAY INVISIBLE (-4600 2900);
FORCEPROP 1 LASTPIN (-4650 2800) $PN 1
J 0
(-4640 2780);
DISPLAY 0.489362 (-4640 2780);
PAINT GREEN (-4640 2780);
FORCEPROP 1 LASTPIN (-4650 2600) $PN 2
J 0
(-4640 2580);
DISPLAY 0.489362 (-4640 2580);
PAINT GREEN (-4640 2580);
FORCEPROP 1 LAST MATERIAL X7R
J 0
(-4550 2650);
DISPLAY 0.489362 (-4550 2650);
PAINT SKYBLUE (-4550 2650);
FORCEPROP 1 LAST TOLERANCE 10%
J 0
(-4550 2700);
DISPLAY 0.489362 (-4550 2700);
PAINT SKYBLUE (-4550 2700);
FORCEPROP 1 LAST VALUE 0.1UF
J 0
(-4550 2800);
DISPLAY 0.489362 (-4550 2800);
PAINT SKYBLUE (-4550 2800);
FORCEPROP 1 LAST VOLTAGE 16V
J 0
(-4550 2750);
DISPLAY 0.489362 (-4550 2750);
PAINT SKYBLUE (-4550 2750);
FORCEPROP 1 LAST PACK_TYPE C0402
J 0
(-4550 2550);
DISPLAY 0.489362 (-4550 2550);
PAINT SKYBLUE (-4550 2550);
FORCEPROP 2 LAST CDS_LIB pure_quanta
J 0
(-4650 2700);
DISPLAY INVISIBLE (-4650 2700);
FORCEPROP 1 LAST PATH I66
J 0
(-4600 2850);
DISPLAY 0.978723 (-4600 2850);
PAINT WHITE (-4600 2850);
DISPLAY INVISIBLE (-4600 2850);
FORCEPROP 1 LAST PART_NUMBER CH4103K1B08
J 0
(-4550 2600);
DISPLAY 0.489362 (-4550 2600);
PAINT SKYBLUE (-4550 2600);
DISPLAY INVISIBLE (-4550 2600);
FORCEADD UNIVERSAL_POWER..1
(-6025 2975);
FORCEPROP 3 LASTPIN (-6025 2925) SIG_NAME PVDD18_S5_P0\g
J 0
(-6015 2935);
DISPLAY 0.659574 (-6015 2935);
PAINT MONO (-6015 2935);
DISPLAY INVISIBLE (-6015 2935);
FORCEPROP 1 LAST HDL_POWER PVDD18_S5_P0
J 1
(-6025 3025);
DISPLAY 0.489362 (-6025 3025);
PAINT GREEN (-6025 3025);
FORCEPROP 2 LAST CDS_LIB pure_quanta_power
J 0
(-6025 2975);
PAINT MONO (-6025 2975);
DISPLAY INVISIBLE (-6025 2975);
FORCEPROP 1 LAST PATH I67
J 0
(-5975 3000);
DISPLAY 0.872340 (-5975 3000);
PAINT AQUA (-5975 3000);
DISPLAY INVISIBLE (-5975 3000);
FORCEADD GND..1
(-6225 2475);
FORCEPROP 3 LASTPIN (-6225 2525) SIG_NAME GND\g
J 0
(-6215 2535);
DISPLAY 0.659574 (-6215 2535);
PAINT MONO (-6215 2535);
DISPLAY INVISIBLE (-6215 2535);
FORCEPROP 2 LAST CDS_LIB pure_quanta_power
J 0
(-6225 2475);
DISPLAY INVISIBLE (-6225 2475);
FORCEPROP 1 LAST SIZE 1B
J 0
(-6150 2425);
DISPLAY 0.872340 (-6150 2425);
PAINT GREEN (-6150 2425);
DISPLAY INVISIBLE (-6150 2425);
FORCEPROP 1 LAST HDL_POWER GND
J 0
(-6225 2625);
DISPLAY 0.872340 (-6225 2625);
PAINT GREEN (-6225 2625);
DISPLAY INVISIBLE (-6225 2625);
FORCEPROP 1 LAST PATH I68
J 0
(-6150 2475);
DISPLAY 0.872340 (-6150 2475);
PAINT AQUA (-6150 2475);
DISPLAY INVISIBLE (-6150 2475);
FORCEADD Q_CAP..1
(-6225 2700);
FORCEPROP 1 LAST LOCATION C1513
J 0
(-6375 2825);
DISPLAY 0.489362 (-6375 2825);
PAINT SKYBLUE (-6375 2825);
FORCEPROP 2 LAST $SEC 1
J 0
(-6175 2900);
PAINT MONO (-6175 2900);
DISPLAY INVISIBLE (-6175 2900);
FORCEPROP 2 LAST CDS_SEC 1
J 0
(-6175 2900);
PAINT MONO (-6175 2900);
DISPLAY INVISIBLE (-6175 2900);
FORCEPROP 1 LASTPIN (-6225 2800) $PN 1
J 0
(-6215 2780);
DISPLAY 0.489362 (-6215 2780);
PAINT GREEN (-6215 2780);
FORCEPROP 1 LASTPIN (-6225 2600) $PN 2
J 0
(-6215 2580);
DISPLAY 0.489362 (-6215 2580);
PAINT GREEN (-6215 2580);
FORCEPROP 1 LAST TOLERANCE 10%
J 0
(-6350 2675);
DISPLAY 0.489362 (-6350 2675);
PAINT SKYBLUE (-6350 2675);
FORCEPROP 1 LAST VALUE 0.1UF
J 0
(-6400 2775);
DISPLAY 0.489362 (-6400 2775);
PAINT SKYBLUE (-6400 2775);
FORCEPROP 1 LAST VOLTAGE 16V
J 0
(-6350 2725);
DISPLAY 0.489362 (-6350 2725);
PAINT SKYBLUE (-6350 2725);
FORCEPROP 1 LAST MATERIAL X7R
J 0
(-6350 2625);
DISPLAY 0.489362 (-6350 2625);
PAINT SKYBLUE (-6350 2625);
FORCEPROP 1 LAST PACK_TYPE C0402
J 0
(-6400 2525);
DISPLAY 0.489362 (-6400 2525);
PAINT SKYBLUE (-6400 2525);
FORCEPROP 2 LAST CDS_LIB pure_quanta
J 0
(-6225 2700);
DISPLAY INVISIBLE (-6225 2700);
FORCEPROP 1 LAST PATH I69
J 0
(-6175 2850);
DISPLAY 0.978723 (-6175 2850);
PAINT WHITE (-6175 2850);
DISPLAY INVISIBLE (-6175 2850);
FORCEPROP 1 LAST PART_NUMBER CH4103K1B08
J 0
(-6575 2575);
DISPLAY 0.489362 (-6575 2575);
PAINT SKYBLUE (-6575 2575);
DISPLAY INVISIBLE (-6575 2575);
FORCEADD GND..1
(-6600 1525);
FORCEPROP 3 LASTPIN (-6600 1575) SIG_NAME GND\g
J 0
(-6590 1585);
DISPLAY 0.659574 (-6590 1585);
PAINT MONO (-6590 1585);
DISPLAY INVISIBLE (-6590 1585);
FORCEPROP 1 LAST SIZE 1B
J 0
(-6525 1475);
DISPLAY 0.872340 (-6525 1475);
PAINT GREEN (-6525 1475);
DISPLAY INVISIBLE (-6525 1475);
FORCEPROP 2 LAST CDS_LIB pure_quanta_power
J 0
(-6600 1525);
PAINT MONO (-6600 1525);
DISPLAY INVISIBLE (-6600 1525);
FORCEPROP 1 LAST HDL_POWER GND
J 0
(-6600 1675);
DISPLAY 0.872340 (-6600 1675);
PAINT GREEN (-6600 1675);
DISPLAY INVISIBLE (-6600 1675);
FORCEPROP 1 LAST PATH I70
J 0
(-6525 1525);
DISPLAY 0.872340 (-6525 1525);
PAINT AQUA (-6525 1525);
DISPLAY INVISIBLE (-6525 1525);
FORCEADD Q_RES..2
R 2
(-6600 1800);
FORCEPROP 1 LAST LOCATION R1637
J 2
(-6645 1925);
DISPLAY 0.489362 (-6645 1925);
PAINT SKYBLUE (-6645 1925);
FORCEPROP 0 LAST $SEC 1
J 0
(-6625 1975);
DISPLAY 0.680851 (-6625 1975);
PAINT MONO (-6625 1975);
DISPLAY INVISIBLE (-6625 1975);
FORCEPROP 0 LAST CDS_SEC 1
J 0
(-6625 1975);
DISPLAY 1.021277 (-6625 1975);
DISPLAY INVISIBLE (-6625 1975);
FORCEPROP 1 LASTPIN (-6600 1900) $PN 1
J 2
(-6605 1862);
DISPLAY 0.489362 (-6605 1862);
PAINT MONO (-6605 1862);
FORCEPROP 1 LASTPIN (-6600 1700) $PN 2
J 2
(-6605 1710);
DISPLAY 0.489362 (-6605 1710);
PAINT MONO (-6605 1710);
FORCEPROP 1 LAST WATTAGE 1/16W
J 2
(-6640 1775);
DISPLAY 0.489362 (-6640 1775);
PAINT SKYBLUE (-6640 1775);
FORCEPROP 1 LAST MATERIAL CHIP
J 2
(-6640 1725);
DISPLAY 0.489362 (-6640 1725);
PAINT SKYBLUE (-6640 1725);
FORCEPROP 1 LAST PACK_TYPE 0402LF
J 2
(-6640 1625);
DISPLAY 0.489362 (-6640 1625);
PAINT SKYBLUE (-6640 1625);
FORCEPROP 1 LAST TOLERANCE 5%
J 2
(-6650 1825);
DISPLAY 0.489362 (-6650 1825);
PAINT SKYBLUE (-6650 1825);
FORCEPROP 1 LAST VALUE 4.7K
J 2
(-6650 1875);
DISPLAY 0.489362 (-6650 1875);
PAINT SKYBLUE (-6650 1875);
FORCEPROP 2 LAST CDS_LIB pure_quanta
J 2
(-6600 1800);
DISPLAY INVISIBLE (-6600 1800);
FORCEPROP 1 LAST PATH I71
J 2
(-6650 1975);
DISPLAY 0.978723 (-6650 1975);
PAINT WHITE (-6650 1975);
DISPLAY INVISIBLE (-6650 1975);
FORCEPROP 1 LAST PART_NUMBER CS24702JB10
J 2
(-6640 1675);
DISPLAY 0.489362 (-6640 1675);
PAINT SKYBLUE (-6640 1675);
DISPLAY INVISIBLE (-6640 1675);
FORCEADD OFFPAGE..2
(-3400 2250);
FORCEPROP 2 LAST $XR0 174 
J 0
(-3211 2250);
DISPLAY 0.638298 (-3211 2250);
PAINT MONO (-3211 2250);
FORCEPROP 2 LAST CDS_LIB standard
J 0
(-3400 2250);
DISPLAY INVISIBLE (-3400 2250);
FORCEPROP 1 LAST OFFPAGE TRUE
J 0
(-3075 2125);
DISPLAY 0.872340 (-3075 2125);
PAINT GREEN (-3075 2125);
DISPLAY INVISIBLE (-3075 2125);
FORCEPROP 1 LAST COMMENT_BODY TRUE
J 0
(-3445 2155);
DISPLAY 0.872340 (-3445 2155);
PAINT GREEN (-3445 2155);
DISPLAY INVISIBLE (-3445 2155);
FORCEPROP 2 LAST PATH I72
J 0
(-3225 2325);
DISPLAY 1.021277 (-3225 2325);
DISPLAY INVISIBLE (-3225 2325);
FORCEADD OFFPAGE..1
R 2
(-3950 2100);
FORCEPROP 2 LAST $XR0 174 
J 0
(-3764 2100);
DISPLAY 0.638298 (-3764 2100);
PAINT MONO (-3764 2100);
FORCEPROP 2 LAST CDS_LIB standard
J 2
(-3950 2100);
DISPLAY INVISIBLE (-3950 2100);
FORCEPROP 1 LAST OFFPAGE TRUE
J 2
(-4275 1975);
DISPLAY 0.872340 (-4275 1975);
PAINT GREEN (-4275 1975);
DISPLAY INVISIBLE (-4275 1975);
FORCEPROP 1 LAST COMMENT_BODY TRUE
J 2
(-4075 2000);
DISPLAY 0.872340 (-4075 2000);
PAINT GREEN (-4075 2000);
DISPLAY INVISIBLE (-4075 2000);
FORCEPROP 2 LAST PATH I73
J 2
(-4000 2175);
DISPLAY 1.021277 (-4000 2175);
DISPLAY INVISIBLE (-4000 2175);
FORCEADD OFFPAGE..1
(-6325 5200);
FORCEPROP 2 LAST $XR0 81 
J 0
(-6576 5200);
DISPLAY 0.638298 (-6576 5200);
PAINT MONO (-6576 5200);
FORCEPROP 2 LAST CDS_LIB standard
J 0
(-6325 5200);
DISPLAY INVISIBLE (-6325 5200);
FORCEPROP 1 LAST OFFPAGE TRUE
J 0
(-6000 5075);
DISPLAY 0.872340 (-6000 5075);
PAINT GREEN (-6000 5075);
DISPLAY INVISIBLE (-6000 5075);
FORCEPROP 1 LAST COMMENT_BODY TRUE
J 0
(-6200 5100);
DISPLAY 0.872340 (-6200 5100);
PAINT GREEN (-6200 5100);
DISPLAY INVISIBLE (-6200 5100);
FORCEPROP 2 LAST PATH I74
J 0
(-6575 5250);
DISPLAY 1.021277 (-6575 5250);
DISPLAY INVISIBLE (-6575 5250);
FORCEADD OFFPAGE..1
(-6325 3525);
FORCEPROP 2 LAST $XR0 81 
J 0
(-6576 3525);
DISPLAY 0.638298 (-6576 3525);
PAINT MONO (-6576 3525);
FORCEPROP 2 LAST CDS_LIB standard
J 0
(-6325 3525);
DISPLAY INVISIBLE (-6325 3525);
FORCEPROP 1 LAST OFFPAGE TRUE
J 0
(-6000 3400);
DISPLAY 0.872340 (-6000 3400);
PAINT GREEN (-6000 3400);
DISPLAY INVISIBLE (-6000 3400);
FORCEPROP 1 LAST COMMENT_BODY TRUE
J 0
(-6200 3425);
DISPLAY 0.872340 (-6200 3425);
PAINT GREEN (-6200 3425);
DISPLAY INVISIBLE (-6200 3425);
FORCEPROP 2 LAST PATH I75
J 0
(-6275 3600);
DISPLAY 1.021277 (-6275 3600);
DISPLAY INVISIBLE (-6275 3600);
FORCEADD Q_RES..1
(-4200 2250);
FORCEPROP 1 LAST LOCATION R6103
J 0
(-4075 2250);
DISPLAY 0.489362 (-4075 2250);
PAINT SKYBLUE (-4075 2250);
FORCEPROP 0 LAST $SEC 1
J 0
(-4075 2300);
DISPLAY 0.680851 (-4075 2300);
PAINT MONO (-4075 2300);
DISPLAY INVISIBLE (-4075 2300);
FORCEPROP 0 LAST CDS_SEC 1
J 0
(-4075 2300);
DISPLAY 0.680851 (-4075 2300);
DISPLAY INVISIBLE (-4075 2300);
FORCEPROP 1 LASTPIN (-4300 2250) $PN 1
J 0
(-4288 2262);
DISPLAY 0.489362 (-4288 2262);
PAINT MONO (-4288 2262);
FORCEPROP 1 LASTPIN (-4100 2250) $PN 2
J 0
(-4138 2262);
DISPLAY 0.489362 (-4138 2262);
PAINT MONO (-4138 2262);
FORCEPROP 1 LAST VALUE 0
J 2
(-4325 2250);
DISPLAY 0.489362 (-4325 2250);
PAINT SKYBLUE (-4325 2250);
FORCEPROP 2 LAST CDS_LIB pure_quanta
J 0
(-4200 2250);
DISPLAY INVISIBLE (-4200 2250);
FORCEPROP 2 LAST BOM_COST MEM
J 2
(-4175 2400);
DISPLAY 0.744681 (-4175 2400);
PAINT WHITE (-4175 2400);
DISPLAY INVISIBLE (-4175 2400);
FORCEPROP 1 LAST WATTAGE 1/16W
J 2
(-4275 2175);
DISPLAY 0.489362 (-4275 2175);
PAINT SKYBLUE (-4275 2175);
DISPLAY INVISIBLE (-4275 2175);
FORCEPROP 1 LAST MATERIAL CHIP
J 2
(-4025 2225);
DISPLAY 0.489362 (-4025 2225);
PAINT SKYBLUE (-4025 2225);
DISPLAY INVISIBLE (-4025 2225);
FORCEPROP 1 LAST TOLERANCE 5%
J 0
(-4325 2225);
DISPLAY 0.489362 (-4325 2225);
PAINT SKYBLUE (-4325 2225);
DISPLAY INVISIBLE (-4325 2225);
FORCEPROP 1 LAST PACK_TYPE 0402LF
J 2
(-4025 2175);
DISPLAY 0.489362 (-4025 2175);
PAINT SKYBLUE (-4025 2175);
DISPLAY INVISIBLE (-4025 2175);
FORCEPROP 1 LAST PATH I76
J 0
(-4250 2400);
DISPLAY 0.978723 (-4250 2400);
PAINT WHITE (-4250 2400);
DISPLAY INVISIBLE (-4250 2400);
FORCEPROP 1 LAST PART_NUMBER CS00002JB13
J 2
(-4075 2175);
DISPLAY 0.489362 (-4075 2175);
PAINT SKYBLUE (-4075 2175);
DISPLAY INVISIBLE (-4075 2175);
FORCEADD Q_RES..1
(-6775 2150);
FORCEPROP 1 LAST LOCATION R6109
J 0
(-6825 2200);
DISPLAY 0.489362 (-6825 2200);
PAINT SKYBLUE (-6825 2200);
FORCEPROP 0 LAST $SEC 1
J 0
(-6825 2225);
DISPLAY 0.680851 (-6825 2225);
PAINT MONO (-6825 2225);
DISPLAY INVISIBLE (-6825 2225);
FORCEPROP 0 LAST CDS_SEC 1
J 0
(-6825 2225);
DISPLAY 0.680851 (-6825 2225);
DISPLAY INVISIBLE (-6825 2225);
FORCEPROP 1 LASTPIN (-6875 2150) $PN 1
J 0
(-6863 2162);
DISPLAY 0.787234 (-6863 2162);
PAINT MONO (-6863 2162);
FORCEPROP 1 LASTPIN (-6675 2150) $PN 2
J 0
(-6713 2162);
DISPLAY 0.787234 (-6713 2162);
PAINT MONO (-6713 2162);
FORCEPROP 1 LAST VALUE 0
J 2
(-6625 2150);
DISPLAY 0.489362 (-6625 2150);
PAINT SKYBLUE (-6625 2150);
FORCEPROP 1 LAST MATERIAL CHIP
J 0
(-6700 2125);
DISPLAY 0.489362 (-6700 2125);
PAINT SKYBLUE (-6700 2125);
FORCEPROP 1 LAST WATTAGE 1/16W
J 2
(-6800 2000);
DISPLAY 0.978723 (-6800 2000);
PAINT SKYBLUE (-6800 2000);
DISPLAY INVISIBLE (-6800 2000);
FORCEPROP 1 LAST TOLERANCE 5%
J 0
(-6775 2050);
DISPLAY 0.978723 (-6775 2050);
PAINT SKYBLUE (-6775 2050);
DISPLAY INVISIBLE (-6775 2050);
FORCEPROP 1 LAST PACK_TYPE 0402LF
J 0
(-6525 2000);
DISPLAY 0.978723 (-6525 2000);
PAINT SKYBLUE (-6525 2000);
DISPLAY INVISIBLE (-6525 2000);
FORCEPROP 2 LAST CDS_LIB pure_quanta
J 0
(-6775 2150);
DISPLAY INVISIBLE (-6775 2150);
FORCEPROP 1 LAST PATH I78
J 0
(-6825 2300);
DISPLAY 0.978723 (-6825 2300);
PAINT WHITE (-6825 2300);
DISPLAY INVISIBLE (-6825 2300);
FORCEPROP 1 LAST PART_NUMBER CS00002JB13
J 0
(-6825 2250);
DISPLAY 0.978723 (-6825 2250);
PAINT SKYBLUE (-6825 2250);
DISPLAY INVISIBLE (-6825 2250);
FORCEADD SN74AVC4T774PWR..1
(-5325 5550);
FORCEPROP 1 LAST LOCATION U150
J 0
(-5572 6115);
DISPLAY 0.489362 (-5572 6115);
PAINT SKYBLUE (-5572 6115);
FORCEPROP 0 LAST $SEC 1
J 0
(-5575 6300);
DISPLAY 0.680851 (-5575 6300);
PAINT MONO (-5575 6300);
DISPLAY INVISIBLE (-5575 6300);
FORCEPROP 0 LAST CDS_SEC 1
J 0
(-5575 6300);
DISPLAY 1.021277 (-5575 6300);
DISPLAY INVISIBLE (-5575 6300);
FORCEPROP 0 LASTPIN (-5725 5700) $PN 3
J 2
(-5735 5710);
DISPLAY 0.489362 (-5735 5710);
PAINT MONO (-5735 5710);
FORCEPROP 0 LASTPIN (-5725 5650) $PN 4
J 2
(-5735 5660);
DISPLAY 0.489362 (-5735 5660);
PAINT MONO (-5735 5660);
FORCEPROP 0 LASTPIN (-5725 5600) $PN 5
J 2
(-5735 5610);
DISPLAY 0.489362 (-5735 5610);
PAINT MONO (-5735 5610);
FORCEPROP 0 LASTPIN (-5725 5550) $PN 6
J 2
(-5735 5560);
DISPLAY 0.489362 (-5735 5560);
PAINT MONO (-5735 5560);
FORCEPROP 0 LASTPIN (-4925 5700) $PN 14
J 0
(-4915 5710);
DISPLAY 0.489362 (-4915 5710);
PAINT MONO (-4915 5710);
FORCEPROP 0 LASTPIN (-4925 5650) $PN 13
J 0
(-4915 5660);
DISPLAY 0.489362 (-4915 5660);
PAINT MONO (-4915 5660);
FORCEPROP 0 LASTPIN (-4925 5600) $PN 12
J 0
(-4915 5610);
DISPLAY 0.489362 (-4915 5610);
PAINT MONO (-4915 5610);
FORCEPROP 0 LASTPIN (-4925 5550) $PN 11
J 0
(-4915 5560);
DISPLAY 0.489362 (-4915 5560);
PAINT MONO (-4915 5560);
FORCEPROP 0 LASTPIN (-5725 5400) $PN 1
J 2
(-5735 5410);
DISPLAY 0.489362 (-5735 5410);
PAINT MONO (-5735 5410);
FORCEPROP 0 LASTPIN (-5725 5350) $PN 2
J 2
(-5735 5360);
DISPLAY 0.489362 (-5735 5360);
PAINT MONO (-5735 5360);
FORCEPROP 0 LASTPIN (-5725 5300) $PN 7
J 2
(-5735 5310);
DISPLAY 0.489362 (-5735 5310);
PAINT MONO (-5735 5310);
FORCEPROP 0 LASTPIN (-5725 5250) $PN 8
J 2
(-5735 5260);
DISPLAY 0.489362 (-5735 5260);
PAINT MONO (-5735 5260);
FORCEPROP 0 LASTPIN (-4925 5150) $PN 10
J 0
(-4915 5160);
DISPLAY 0.489362 (-4915 5160);
PAINT MONO (-4915 5160);
FORCEPROP 0 LASTPIN (-5725 5200) $PN 9
J 2
(-5735 5210);
DISPLAY 0.489362 (-5735 5210);
PAINT MONO (-5735 5210);
FORCEPROP 0 LASTPIN (-5725 5900) $PN 16
J 2
(-5735 5910);
DISPLAY 0.489362 (-5735 5910);
PAINT MONO (-5735 5910);
FORCEPROP 0 LASTPIN (-4925 5900) $PN 15
J 0
(-4915 5910);
DISPLAY 0.489362 (-4915 5910);
PAINT MONO (-4915 5910);
FORCEPROP 2 LAST PART_TYPE SMLF
J 0
(-5575 6250);
PAINT MONO (-5575 6250);
FORCEPROP 1 LAST MATERIAL IC
J 0
(-5572 6003);
DISPLAY 0.489362 (-5572 6003);
PAINT SKYBLUE (-5572 6003);
FORCEPROP 2 LAST VALUE SN74AVC4T774PWR
J 0
(-5575 6175);
DISPLAY 0.489362 (-5575 6175);
PAINT SKYBLUE (-5575 6175);
FORCEPROP 1 LAST NEEDS_NO_SIZE TRUE
J 0
(-5325 5550);
DISPLAY 0.723404 (-5325 5550);
PAINT GREEN (-5325 5550);
DISPLAY INVISIBLE (-5325 5550);
FORCEPROP 1 LAST CDS_LMAN_SYM_OUTLINE -250,450,250,-450
J 0
(-5325 5550);
DISPLAY 0.468085 (-5325 5550);
PAINT GREEN (-5325 5550);
DISPLAY INVISIBLE (-5325 5550);
FORCEPROP 2 LAST CDS_LIB pure_quanta
J 0
(-5325 5550);
DISPLAY INVISIBLE (-5325 5550);
FORCEPROP 1 LAST PATH I8
J 0
(-5325 5550);
DISPLAY 0.723404 (-5325 5550);
PAINT GREEN (-5325 5550);
DISPLAY INVISIBLE (-5325 5550);
FORCEPROP 1 LAST PART_NUMBER AL04T774K00
J 0
(-5572 6058);
DISPLAY 0.489362 (-5572 6058);
PAINT SKYBLUE (-5572 6058);
DISPLAY INVISIBLE (-5572 6058);
FORCEADD OFFPAGE..1
(-7625 5700);
FORCEPROP 2 LAST $XR0 172 
J 0
(-7877 5700);
DISPLAY 0.638298 (-7877 5700);
PAINT MONO (-7877 5700);
FORCEPROP 2 LAST CDS_LIB standard
J 2
(-7625 5700);
DISPLAY INVISIBLE (-7625 5700);
FORCEPROP 1 LAST OFFPAGE TRUE
J 0
(-7300 5575);
DISPLAY 0.872340 (-7300 5575);
PAINT GREEN (-7300 5575);
DISPLAY INVISIBLE (-7300 5575);
FORCEPROP 1 LAST COMMENT_BODY TRUE
J 0
(-7500 5600);
DISPLAY 0.872340 (-7500 5600);
PAINT GREEN (-7500 5600);
DISPLAY INVISIBLE (-7500 5600);
FORCEPROP 2 LAST PATH I9
J 2
(-7800 5775);
DISPLAY 1.021277 (-7800 5775);
DISPLAY INVISIBLE (-7800 5775);
FORCEADD CAD_NOTE..1
(-7475 2025);
FORCEPROP 0 LAST L1 R6109 PLACE CLOSE TO U152
J 0
(-7625 1900);
DISPLAY 0.617021 (-7625 1900);
PAINT WHITE (-7625 1900);
FORCEPROP 2 LAST CDS_LIB pure_quanta_power
J 0
(-7475 2025);
DISPLAY INVISIBLE (-7475 2025);
FORCEPROP 1 LAST COMMENT_BODY TRUE
J 0
(-7450 2125);
DISPLAY 0.574468 (-7450 2125);
PAINT WHITE (-7450 2125);
DISPLAY INVISIBLE (-7450 2125);
FORCEADD QUANTA_TITLE_BLOCK_C..1
(0 0);
FORCEPROP 0 LAST CDS_CON_LAST_MODIFIED Thu Sep 14 16:12:16 2023
J 0
(-1885 15);
DISPLAY INVISIBLE (-1885 15);
FORCEPROP 1 LAST CUSTOM_TXT_CDS <CON_LAST_MODIFIED>
J 0
(-1885 15);
DISPLAY 0.978723 (-1885 15);
FORCEPROP 2 LAST CUSTOM_TXT_CDS <XR_PAGE_TITLE>
J 0
(-7890 5250);
DISPLAY 0.638298 (-7890 5250);
PAINT PINK (-7890 5250);
DISPLAY INVISIBLE (-7890 5250);
FORCEPROP 1 LAST CUSTOM_TXT_CDS <NAME_2>
J 0
(-3175 50);
FORCEPROP 1 LAST CUSTOM_TXT_CDS <NAME_1>
J 0
(-3175 175);
FORCEPROP 1 LAST CUSTOM_TXT_CDS <Q_NUMBER>
J 0
(-1403 103);
DISPLAY 1.212766 (-1403 103);
FORCEPROP 1 LAST CUSTOM_TXT_CDS <Q_PROJ>
J 0
(-2382 102);
DISPLAY 1.212766 (-2382 102);
FORCEPROP 1 LAST CUSTOM_TXT_CDS <Q_REV>
J 0
(-184 103);
DISPLAY 1.212766 (-184 103);
FORCEPROP 1 LAST CUSTOM_TXT_CDS <CON_PAGE_NUM> OF <CON_TOTAL_PAGES>
J 0
(-446 18);
DISPLAY 0.978723 (-446 18);
FORCEPROP 1 LAST Q_TITLE JTAG - BUFFER
J 0
(-9225 100);
DISPLAY 2.446809 (-9225 100);
PAINT GREEN (-9225 100);
FORCEPROP 1 LAST CDS_LMAN_SYM_OUTLINE -9475,6775,100,-125
J 0
(0 0);
DISPLAY 0.468085 (0 0);
PAINT GREEN (0 0);
DISPLAY INVISIBLE (0 0);
FORCEPROP 2 LAST CDS_LIB pure_quanta
J 0
(0 0);
DISPLAY INVISIBLE (0 0);
FORCEPROP 2 LAST PAGE_BORDER TRUE
J 0
(-7890 5250);
DISPLAY 0.638298 (-7890 5250);
PAINT PINK (-7890 5250);
DISPLAY INVISIBLE (-7890 5250);
FORCEPROP 2 LAST CDS_XR_PAGE_TITLE CR-173 : @T6G_MB_LIB.T6G(SCH_1):PAGE173
J 0
(-7890 5250);
DISPLAY 0.638298 (-7890 5250);
PAINT PINK (-7890 5250);
DISPLAY INVISIBLE (-7890 5250);
FORCEPROP 1 LAST Q_DEPT BU9
J 1
(-3763 49);
DISPLAY 1.957447 (-3763 49);
PAINT GREEN (-3763 49);
DISPLAY INVISIBLE (-3763 49);
FORCEPROP 1 LAST COMMENT_BODY TRUE
J 0
(12 -13);
DISPLAY 0.978723 (12 -13);
PAINT GREEN (12 -13);
DISPLAY INVISIBLE (12 -13);
FORCEADD CAD_NOTE..1
(-4150 2500);
FORCEPROP 0 LAST L1 R6103 PLACE CLOSE TO U152
J 0
(-4300 2375);
DISPLAY 0.617021 (-4300 2375);
PAINT WHITE (-4300 2375);
FORCEPROP 2 LAST CDS_LIB pure_quanta_power
J 0
(-4150 2500);
DISPLAY INVISIBLE (-4150 2500);
FORCEPROP 1 LAST COMMENT_BODY TRUE
J 0
(-4125 2600);
DISPLAY 0.574468 (-4125 2600);
PAINT WHITE (-4125 2600);
DISPLAY INVISIBLE (-4125 2600);
WIRE 16 -1 (-4650 6000)(-4650 5925);
WIRE 16 -1 (-6050 6000)(-6050 5975);
WIRE 16 -1 (-4650 4300)(-4650 4225);
WIRE 16 -1 (-6050 4350)(-6050 4275);
WIRE 16 -1 (-4650 2600)(-4650 2525);
WIRE 16 -1 (-6225 2600)(-6225 2525);
WIRE 16 -1 (-6600 1575)(-6600 1700);
WIRE 16 -1 (-4925 4225)(-4800 4225);
WIRE 16 -1 (-4800 4225)(-4800 4575);
WIRE 16 -1 (-4800 4675)(-4800 4575);
WIRE 16 -1 (-4650 4575)(-4800 4575);
WIRE 16 -1 (-4650 4500)(-4650 4575);
WIRE 16 -1 (-7575 5700)(-6650 5700);
FORCEPROP 2 LAST SIG_NAME JTAG_TCK
J 0
(-7510 5710);
DISPLAY 0.489362 (-7510 5710);
WIRE 16 -1 (-6650 5700)(-5725 5700);
WIRE 16 -1 (-6650 4025)(-6650 5700);
WIRE 16 -1 (-6650 4025)(-5725 4025);
WIRE 16 -1 (-5725 5650)(-6700 5650);
WIRE 16 -1 (-6700 5650)(-7575 5650);
FORCEPROP 2 LAST SIG_NAME JTAG_TMS
J 0
(-7510 5660);
DISPLAY 0.489362 (-7510 5660);
WIRE 16 -1 (-6700 5650)(-6700 3975);
WIRE 16 -1 (-5725 3975)(-6700 3975);
WIRE 16 -1 (-7575 5550)(-6800 5550);
FORCEPROP 2 LAST SIG_NAME JTAG_DBREQ_N
J 0
(-7510 5560);
DISPLAY 0.489362 (-7510 5560);
WIRE 16 -1 (-6800 5550)(-5725 5550);
WIRE 16 -1 (-6800 5550)(-6800 3875);
WIRE 16 -1 (-5725 3875)(-6800 3875);
WIRE 16 -1 (-7575 5600)(-6750 5600);
FORCEPROP 2 LAST SIG_NAME JTAG_TRST_N
J 0
(-7510 5610);
DISPLAY 0.489362 (-7510 5610);
WIRE 16 -1 (-6750 5600)(-5725 5600);
WIRE 16 -1 (-6750 5600)(-6750 3925);
WIRE 16 -1 (-5725 3925)(-6750 3925);
WIRE 16 -1 (-5725 3575)(-5850 3575);
WIRE 16 -1 (-5850 3625)(-5850 3575);
WIRE 16 -1 (-5725 3625)(-5850 3625);
WIRE 16 -1 (-5850 3675)(-5850 3625);
WIRE 16 -1 (-5725 3675)(-5850 3675);
WIRE 16 -1 (-5850 3725)(-5850 3675);
WIRE 16 -1 (-5850 3725)(-5850 4225);
WIRE 16 -1 (-5725 3725)(-5850 3725);
WIRE 16 -1 (-5725 4225)(-5850 4225);
WIRE 16 -1 (-5850 4225)(-5850 4600);
WIRE 16 -1 (-5850 4675)(-5850 4600);
WIRE 16 -1 (-5850 4600)(-6050 4600);
WIRE 16 -1 (-6050 4550)(-6050 4600);
WIRE 16 -1 (-4925 3475)(-4800 3475);
WIRE 16 -1 (-4800 3400)(-4800 3475);
WIRE 16 -1 (-4925 3875)(-3725 3875);
FORCEPROP 2 LAST SIG_NAME JTAG_P1_R_DBREQ_N
J 0
(-4685 3885);
DISPLAY 0.489362 (-4685 3885);
FORCEPROP 2 LASTPROP $XRERR UNIQUE?
J 0
(-4925 3885);
DISPLAY 0.638298 (-4925 3885);
PAINT MONO (-4925 3885);
DISPLAY INVISIBLE (-4925 3885);
WIRE 16 -1 (-4925 3925)(-3725 3925);
FORCEPROP 2 LAST SIG_NAME JTAG_P1_R_TRST_N
J 0
(-4685 3935);
DISPLAY 0.489362 (-4685 3935);
FORCEPROP 2 LASTPROP $XRERR UNIQUE?
J 0
(-4925 3935);
DISPLAY 0.638298 (-4925 3935);
PAINT MONO (-4925 3935);
DISPLAY INVISIBLE (-4925 3935);
WIRE 16 -1 (-3725 3975)(-4925 3975);
FORCEPROP 2 LAST SIG_NAME JTAG_P1_R_TMS
J 0
(-4685 3985);
DISPLAY 0.489362 (-4685 3985);
FORCEPROP 2 LASTPROP $XRERR UNIQUE?
J 0
(-4925 3985);
DISPLAY 0.638298 (-4925 3985);
PAINT MONO (-4925 3985);
DISPLAY INVISIBLE (-4925 3985);
WIRE 16 -1 (-4925 4025)(-3725 4025);
FORCEPROP 2 LAST SIG_NAME JTAG_P1_R_TCK
J 0
(-4685 4035);
DISPLAY 0.489362 (-4685 4035);
FORCEPROP 2 LASTPROP $XRERR UNIQUE?
J 0
(-4925 4035);
DISPLAY 0.638298 (-4925 4035);
PAINT MONO (-4925 4035);
DISPLAY INVISIBLE (-4925 4035);
WIRE 16 -1 (-6275 3525)(-5725 3525);
FORCEPROP 2 LAST SIG_NAME CPU1_JTAG_BUF_OE
J 0
(-6210 3535);
DISPLAY 0.489362 (-6210 3535);
WIRE 16 -1 (-4925 5550)(-3725 5550);
FORCEPROP 2 LAST SIG_NAME JTAG_P0_R_DBREQ_N
J 0
(-4685 5560);
DISPLAY 0.489362 (-4685 5560);
FORCEPROP 2 LASTPROP $XRERR UNIQUE?
J 0
(-4925 5560);
DISPLAY 0.638298 (-4925 5560);
PAINT MONO (-4925 5560);
DISPLAY INVISIBLE (-4925 5560);
WIRE 16 -1 (-3525 5550)(-2425 5550);
FORCEPROP 2 LAST SIG_NAME JTAG_CPU0_DBREQ_N
J 0
(-3360 5560);
DISPLAY 0.489362 (-3360 5560);
WIRE 16 -1 (-3525 3875)(-2375 3875);
FORCEPROP 2 LAST SIG_NAME JTAG_CPU1_DBREQ_N
J 0
(-3335 3885);
DISPLAY 0.489362 (-3335 3885);
WIRE 16 -1 (-2375 3925)(-3525 3925);
FORCEPROP 2 LAST SIG_NAME JTAG_CPU1_TRST_N
J 0
(-3335 3935);
DISPLAY 0.489362 (-3335 3935);
WIRE 16 -1 (-2375 3975)(-3525 3975);
FORCEPROP 2 LAST SIG_NAME JTAG_CPU1_TMS
J 0
(-3335 3985);
DISPLAY 0.489362 (-3335 3985);
WIRE 16 -1 (-3525 4025)(-2375 4025);
FORCEPROP 2 LAST SIG_NAME JTAG_CPU1_TCK
J 0
(-3335 4035);
DISPLAY 0.489362 (-3335 4035);
WIRE 16 -1 (-4925 5700)(-3725 5700);
FORCEPROP 2 LAST SIG_NAME JTAG_P0_R_TCK
J 0
(-4685 5710);
DISPLAY 0.489362 (-4685 5710);
FORCEPROP 2 LASTPROP $XRERR UNIQUE?
J 0
(-4925 5710);
DISPLAY 0.638298 (-4925 5710);
PAINT MONO (-4925 5710);
DISPLAY INVISIBLE (-4925 5710);
WIRE 16 -1 (-2425 5700)(-3525 5700);
FORCEPROP 2 LAST SIG_NAME JTAG_CPU0_TCK
J 0
(-3360 5710);
DISPLAY 0.489362 (-3360 5710);
WIRE 16 -1 (-4925 5600)(-3725 5600);
FORCEPROP 2 LAST SIG_NAME JTAG_P0_R_TRST_N
J 0
(-4685 5610);
DISPLAY 0.489362 (-4685 5610);
FORCEPROP 2 LASTPROP $XRERR UNIQUE?
J 0
(-4925 5610);
DISPLAY 0.638298 (-4925 5610);
PAINT MONO (-4925 5610);
DISPLAY INVISIBLE (-4925 5610);
WIRE 16 -1 (-3525 5600)(-2425 5600);
FORCEPROP 2 LAST SIG_NAME JTAG_CPU0_TRST_N
J 0
(-3360 5610);
DISPLAY 0.489362 (-3360 5610);
WIRE 16 -1 (-3725 5650)(-4925 5650);
FORCEPROP 2 LAST SIG_NAME JTAG_P0_R_TMS
J 0
(-4685 5660);
DISPLAY 0.489362 (-4685 5660);
FORCEPROP 2 LASTPROP $XRERR UNIQUE?
J 0
(-4925 5660);
DISPLAY 0.638298 (-4925 5660);
PAINT MONO (-4925 5660);
DISPLAY INVISIBLE (-4925 5660);
WIRE 16 -1 (-2425 5650)(-3525 5650);
FORCEPROP 2 LAST SIG_NAME JTAG_CPU0_TMS
J 0
(-3360 5660);
DISPLAY 0.489362 (-3360 5660);
WIRE 16 -1 (-7200 2150)(-6875 2150);
FORCEPROP 2 LAST SIG_NAME JTAG_TDO
J 0
(-7160 2160);
DISPLAY 0.489362 (-7160 2160);
WIRE 16 -1 (-6675 2150)(-5725 2150);
FORCEPROP 2 LAST SIG_NAME JTAG_TDO_R
J 0
(-6585 2160);
DISPLAY 0.489362 (-6585 2160);
FORCEPROP 2 LASTPROP $XRERR UNIQUE?
J 0
(-6825 2160);
DISPLAY 0.638298 (-6825 2160);
PAINT MONO (-6825 2160);
DISPLAY INVISIBLE (-6825 2160);
WIRE 16 -1 (-4925 2250)(-4300 2250);
FORCEPROP 2 LAST SIG_NAME JTAG_CPUX_TDI_R1
J 0
(-4785 2260);
DISPLAY 0.489362 (-4785 2260);
FORCEPROP 2 LASTPROP $XRERR UNIQUE?
J 0
(-5025 2260);
DISPLAY 0.638298 (-5025 2260);
PAINT MONO (-5025 2260);
DISPLAY INVISIBLE (-5025 2260);
WIRE 16 -1 (-4100 2250)(-3450 2250);
FORCEPROP 2 LAST SIG_NAME JTAG_CPUX_TDI
J 0
(-3835 2260);
DISPLAY 0.489362 (-3835 2260);
WIRE 16 -1 (-5725 2000)(-6600 2000);
FORCEPROP 2 LAST SIG_NAME U152_OE_N
J 0
(-6560 2010);
DISPLAY 0.489362 (-6560 2010);
FORCEPROP 2 LASTPROP $XRERR UNIQUE?
J 0
(-6800 2010);
DISPLAY 0.638298 (-6800 2010);
PAINT MONO (-6800 2010);
DISPLAY INVISIBLE (-6800 2010);
WIRE 16 -1 (-6600 1900)(-6600 2000);
WIRE 16 -1 (-4925 5900)(-4800 5900);
WIRE 16 -1 (-4800 5900)(-4800 6275);
WIRE 16 -1 (-4650 6275)(-4800 6275);
WIRE 16 -1 (-4800 6375)(-4800 6275);
WIRE 16 -1 (-4650 6200)(-4650 6275);
WIRE 16 -1 (-4925 5150)(-4800 5150);
WIRE 16 -1 (-4800 5025)(-4800 5150);
WIRE 16 -1 (-6050 6200)(-6050 6300);
WIRE 16 -1 (-5850 6300)(-6050 6300);
WIRE 16 -1 (-5850 6375)(-5850 6300);
WIRE 16 -1 (-5850 5900)(-5850 6300);
WIRE 16 -1 (-5725 5900)(-5850 5900);
WIRE 16 -1 (-5850 5400)(-5850 5900);
WIRE 16 -1 (-5725 5400)(-5850 5400);
WIRE 16 -1 (-5850 5400)(-5850 5350);
WIRE 16 -1 (-5725 5350)(-5850 5350);
WIRE 16 -1 (-5850 5350)(-5850 5300);
WIRE 16 -1 (-5725 5300)(-5850 5300);
WIRE 16 -1 (-5850 5300)(-5850 5250);
WIRE 16 -1 (-5725 5250)(-5850 5250);
WIRE 16 -1 (-5725 2100)(-6025 2100);
WIRE 16 -1 (-6025 2100)(-6025 1850);
WIRE 16 -1 (-6025 1850)(-5725 1850);
WIRE 16 -1 (-6025 1850)(-6025 1800);
WIRE 16 -1 (-4650 2800)(-4650 2875);
WIRE 16 -1 (-4650 2875)(-4775 2875);
WIRE 16 -1 (-4775 2925)(-4775 2875);
WIRE 16 -1 (-4775 2875)(-4775 2500);
WIRE 16 -1 (-4775 2450)(-4775 2500);
WIRE 16 -1 (-4925 2500)(-4775 2500);
WIRE 16 -1 (-4925 2450)(-4775 2450);
WIRE 16 -1 (-5725 2250)(-6025 2250);
WIRE 16 -1 (-6025 2250)(-6025 2850);
WIRE 16 -1 (-6025 2850)(-6225 2850);
WIRE 16 -1 (-6025 2850)(-6025 2925);
WIRE 16 -1 (-6225 2800)(-6225 2850);
WIRE 16 -1 (-6275 5200)(-5725 5200);
FORCEPROP 2 LAST SIG_NAME CPU0_JTAG_BUF_OE
J 0
(-6210 5210);
DISPLAY 0.489362 (-6210 5210);
WIRE 16 -1 (-6650 2300)(-5725 2300);
FORCEPROP 2 LAST SIG_NAME JTAG_TDI
J 2
(-6410 2310);
DISPLAY 0.489362 (-6410 2310);
WIRE 16 -1 (-4925 2100)(-4000 2100);
FORCEPROP 2 LAST SIG_NAME JTAG_CPUX_TDO
J 0
(-4660 2110);
DISPLAY 0.489362 (-4660 2110);
DOT 1 (-4800 4575);
DOT 1 (-5850 4225);
DOT 1 (-5850 5300);
DOT 1 (-5850 5350);
DOT 1 (-6800 5550);
DOT 1 (-6025 1850);
DOT 1 (-6025 2850);
DOT 1 (-5850 3625);
DOT 1 (-5850 3675);
DOT 1 (-5850 3725);
DOT 1 (-4775 2500);
DOT 1 (-4775 2875);
DOT 1 (-6750 5600);
DOT 1 (-6700 5650);
DOT 1 (-6650 5700);
DOT 1 (-5850 4600);
DOT 1 (-5850 5400);
DOT 1 (-5850 5900);
DOT 1 (-5850 6300);
DOT 1 (-4800 6275);
FORCENOTE
CPU1
(-2725 4175) 0;
DISPLAY LEFT (-2725 4175);
DISPLAY 2.510638 (-2725 4175);
PAINT WHITE (-2725 4175);
FORCENOTE
CPU0
(-2775 5975) 0;
DISPLAY LEFT (-2775 5975);
DISPLAY 2.510638 (-2775 5975);
PAINT WHITE (-2775 5975);
FORCENOTE
CPU0/1 TDI/TDO DAISY CHAIN 
(-3675 2450) 0;
DISPLAY LEFT (-3675 2450);
DISPLAY 2.510638 (-3675 2450);
PAINT WHITE (-3675 2450);
QUIT
